FILE_TYPE = MACRO_DRAWING;
SET COLOR_WIRE YELLOW;
SET COLOR_PROP ORANGE;
SET COLOR_DOT WHITE;
SET COLOR_ARC YELLOW;
SET COLOR_BODY GREEN;
SET COLOR_NOTE PURPLE;
SET PROP_DISPLAY VALUE;
SET PAGE_NUMBER P295;
FORCEADD OFFPAGE..2
(5550 725);
FORCEPROP 2 LAST $XR0 214 
J 0
(5739 725);
DISPLAY 0.638298 (5739 725);
PAINT MONO (5739 725);
FORCEPROP 1 LAST OFFPAGE TRUE
J 0
(5875 600);
DISPLAY 0.872340 (5875 600);
DISPLAY INVISIBLE (5875 600);
FORCEPROP 1 LAST COMMENT_BODY TRUE
J 0
(5505 630);
DISPLAY 0.872340 (5505 630);
PAINT GREEN (5505 630);
DISPLAY INVISIBLE (5505 630);
FORCEPROP 2 LAST CDS_LIB standard
J 0
(5550 725);
DISPLAY INVISIBLE (5550 725);
FORCEPROP 2 LAST PATH I121
J 0
(5750 775);
DISPLAY 1.021277 (5750 775);
DISPLAY INVISIBLE (5750 775);
FORCEADD Q_RES..1
(4350 725);
FORCEPROP 1 LAST PART_NUMBER CS00002JB13
J 0
(4075 600);
DISPLAY 0.723404 (4075 600);
PAINT WHITE (4075 600);
DISPLAY INVISIBLE (4075 600);
FORCEPROP 1 LAST PACK_TYPE 0402LF
J 0
(4650 725);
DISPLAY 0.574468 (4650 725);
FORCEPROP 1 LAST MATERIAL CHIP
J 0
(4525 725);
DISPLAY 0.574468 (4525 725);
FORCEPROP 1 LAST VALUE 0
J 2
(4500 725);
DISPLAY 0.574468 (4500 725);
FORCEPROP 1 LAST $LOCATION R3752
J 0
(4175 725);
DISPLAY 0.510638 (4175 725);
FORCEPROP 1 LASTPIN (4250 725) $PN 1
J 0
(4262 737);
DISPLAY 0.787234 (4262 737);
PAINT MONO (4262 737);
FORCEPROP 1 LASTPIN (4450 725) $PN 2
J 0
(4412 737);
DISPLAY 0.787234 (4412 737);
PAINT MONO (4412 737);
FORCEPROP 2 LAST CDS_LIB pure_quanta
J 0
(4350 725);
DISPLAY INVISIBLE (4350 725);
FORCEPROP 1 LAST TOLERANCE 5%
J 0
(4150 650);
DISPLAY 0.723404 (4150 650);
PAINT SKYBLUE (4150 650);
DISPLAY INVISIBLE (4150 650);
FORCEPROP 1 LAST WATTAGE 1/16W
J 2
(4425 650);
DISPLAY 0.723404 (4425 650);
PAINT SKYBLUE (4425 650);
DISPLAY INVISIBLE (4425 650);
FORCEPROP 1 LAST PATH I122
J 0
(4300 875);
DISPLAY 0.978723 (4300 875);
PAINT WHITE (4300 875);
DISPLAY INVISIBLE (4300 875);
FORCEPROP 0 LAST CDS_LOCATION R3752
J 0
(4650 775);
DISPLAY 1.021277 (4650 775);
DISPLAY INVISIBLE (4650 775);
FORCEPROP 0 LAST $SEC 1
J 0
(4650 775);
DISPLAY 0.680851 (4650 775);
PAINT MONO (4650 775);
DISPLAY INVISIBLE (4650 775);
FORCEPROP 0 LAST CDS_SEC 1
J 0
(4650 775);
DISPLAY 1.021277 (4650 775);
DISPLAY INVISIBLE (4650 775);
FORCEADD UNIVERSAL_POWER..1
(2425 1475);
FORCEPROP 3 LASTPIN (2425 1425) SIG_NAME P3V3_AUX\g
J 0
(2435 1435);
DISPLAY 0.659574 (2435 1435);
PAINT MONO (2435 1435);
DISPLAY INVISIBLE (2435 1435);
FORCEPROP 1 LAST HDL_POWER P3V3_AUX
J 1
(2425 1525);
DISPLAY 0.872340 (2425 1525);
PAINT GREEN (2425 1525);
FORCEPROP 2 LAST CDS_LIB logical_power
J 0
(2425 1475);
DISPLAY INVISIBLE (2425 1475);
FORCEPROP 1 LAST PATH I123
J 0
(2475 1500);
DISPLAY 0.872340 (2475 1500);
PAINT AQUA (2475 1500);
DISPLAY INVISIBLE (2475 1500);
FORCEADD UNIVERSAL_GND..1
(2175 800);
FORCEPROP 3 LASTPIN (2175 850) SIG_NAME GND\g
J 0
(2185 860);
DISPLAY 0.659574 (2185 860);
PAINT MONO (2185 860);
DISPLAY INVISIBLE (2185 860);
FORCEPROP 1 LAST HDL_POWER GND
J 1
(2200 725);
DISPLAY 0.872340 (2200 725);
PAINT GREEN (2200 725);
DISPLAY INVISIBLE (2200 725);
FORCEPROP 2 LAST CDS_LIB logical_power
J 0
(2175 800);
DISPLAY INVISIBLE (2175 800);
FORCEPROP 1 LAST PATH I124
J 0
(2250 800);
DISPLAY 0.872340 (2250 800);
PAINT AQUA (2250 800);
DISPLAY INVISIBLE (2250 800);
FORCEADD Q_CAP..1
(2175 1075);
FORCEPROP 1 LAST PART_NUMBER CH4104K1B00
J 0
(2225 925);
DISPLAY 0.808511 (2225 925);
DISPLAY INVISIBLE (2225 925);
FORCEPROP 1 LAST VOLTAGE 25V
J 0
(2225 1075);
DISPLAY 0.638298 (2225 1075);
FORCEPROP 1 LAST PACK_TYPE 0402
J 0
(2225 925);
DISPLAY 0.638298 (2225 925);
FORCEPROP 1 LAST MATERIAL X7R
J 0
(2225 975);
DISPLAY 0.638298 (2225 975);
FORCEPROP 1 LAST VALUE 0.1UF
J 0
(2225 1125);
DISPLAY 0.638298 (2225 1125);
FORCEPROP 1 LAST TOLERANCE 10%
J 0
(2225 1025);
DISPLAY 0.638298 (2225 1025);
FORCEPROP 1 LAST $LOCATION C2067
J 0
(2225 1175);
DISPLAY 0.978723 (2225 1175);
FORCEPROP 1 LASTPIN (2175 1175) $PN 1
J 0
(2185 1155);
DISPLAY 0.787234 (2185 1155);
PAINT MONO (2185 1155);
FORCEPROP 1 LASTPIN (2175 975) $PN 2
J 0
(2185 955);
DISPLAY 0.787234 (2185 955);
PAINT MONO (2185 955);
FORCEPROP 2 LAST CDS_LIB pure_quanta
J 0
(2175 1075);
DISPLAY INVISIBLE (2175 1075);
FORCEPROP 1 LAST PATH I125
J 0
(2225 1225);
DISPLAY 0.978723 (2225 1225);
PAINT WHITE (2225 1225);
DISPLAY INVISIBLE (2225 1225);
FORCEPROP 0 LAST CDS_LOCATION C2067
J 0
(2225 1225);
DISPLAY 1.021277 (2225 1225);
DISPLAY INVISIBLE (2225 1225);
FORCEPROP 0 LAST $SEC 1
J 0
(2225 1225);
DISPLAY 0.680851 (2225 1225);
PAINT MONO (2225 1225);
DISPLAY INVISIBLE (2225 1225);
FORCEPROP 0 LAST CDS_SEC 1
J 0
(2225 1225);
DISPLAY 1.021277 (2225 1225);
DISPLAY INVISIBLE (2225 1225);
FORCEADD UNIVERSAL_GND..1
(3400 -175);
FORCEPROP 3 LASTPIN (3400 -125) SIG_NAME GND\g
J 0
(3410 -115);
DISPLAY 0.659574 (3410 -115);
PAINT MONO (3410 -115);
DISPLAY INVISIBLE (3410 -115);
FORCEPROP 2 LAST CDS_LIB logical_power
J 0
(3400 -175);
DISPLAY INVISIBLE (3400 -175);
FORCEPROP 1 LAST HDL_POWER GND
J 1
(3425 -250);
DISPLAY 0.872340 (3425 -250);
PAINT GREEN (3425 -250);
DISPLAY INVISIBLE (3425 -250);
FORCEPROP 1 LAST PATH I128
J 0
(3475 -175);
DISPLAY 0.872340 (3475 -175);
PAINT AQUA (3475 -175);
DISPLAY INVISIBLE (3475 -175);
FORCEADD INA230AIRGTR..1
(2875 475);
FORCEPROP 1 LAST PART_NUMBER AL000230001
J 0
(2628 911);
DISPLAY 0.723404 (2628 911);
PAINT GREEN (2628 911);
DISPLAY INVISIBLE (2628 911);
FORCEPROP 2 LAST PART_TYPE SMLF
J 0
(2600 1150);
DISPLAY 1.021277 (2600 1150);
FORCEPROP 1 LAST MATERIAL IC
J 0
(2628 784);
DISPLAY 0.723404 (2628 784);
PAINT GREEN (2628 784);
FORCEPROP 2 LAST VALUE INA230AIRGTR
J 0
(2600 1100);
DISPLAY 1.021277 (2600 1100);
FORCEPROP 1 LAST $LOCATION U276
J 0
(2628 1058);
DISPLAY 0.723404 (2628 1058);
PAINT GREEN (2628 1058);
FORCEPROP 0 LASTPIN (2475 575) $PN 2
J 2
(2465 585);
DISPLAY 0.680851 (2465 585);
PAINT MONO (2465 585);
FORCEPROP 0 LASTPIN (2475 625) $PN 1
J 2
(2465 635);
DISPLAY 0.680851 (2465 635);
PAINT MONO (2465 635);
FORCEPROP 0 LASTPIN (3275 725) $PN 3
J 0
(3285 735);
DISPLAY 0.680851 (3285 735);
PAINT MONO (3285 735);
FORCEPROP 0 LASTPIN (2475 325) $PN 11
J 2
(2465 335);
DISPLAY 0.680851 (2465 335);
PAINT MONO (2465 335);
FORCEPROP 0 LASTPIN (3275 275) $PN 10
J 0
(3285 285);
DISPLAY 0.680851 (3285 285);
PAINT MONO (3285 285);
FORCEPROP 0 LASTPIN (2475 275) $PN 13
J 2
(2465 285);
DISPLAY 0.680851 (2465 285);
PAINT MONO (2465 285);
FORCEPROP 0 LASTPIN (2475 225) $PN 12
J 2
(2465 235);
DISPLAY 0.680851 (2465 235);
PAINT MONO (2465 235);
FORCEPROP 0 LASTPIN (3275 625) $PN 6
J 0
(3285 635);
DISPLAY 0.680851 (3285 635);
PAINT MONO (3285 635);
FORCEPROP 0 LASTPIN (3275 575) $PN 7
J 0
(3285 585);
DISPLAY 0.680851 (3285 585);
PAINT MONO (3285 585);
FORCEPROP 0 LASTPIN (3275 525) $PN 8
J 0
(3285 535);
DISPLAY 0.680851 (3285 535);
PAINT MONO (3285 535);
FORCEPROP 0 LASTPIN (3275 475) $PN 14
J 0
(3285 485);
DISPLAY 0.680851 (3285 485);
PAINT MONO (3285 485);
FORCEPROP 0 LASTPIN (3275 425) $PN 15
J 0
(3285 435);
DISPLAY 0.680851 (3285 435);
PAINT MONO (3285 435);
FORCEPROP 0 LASTPIN (3275 375) $PN 16
J 0
(3285 385);
DISPLAY 0.680851 (3285 385);
PAINT MONO (3285 385);
FORCEPROP 0 LASTPIN (2475 475) $PN 5
J 2
(2465 485);
DISPLAY 0.680851 (2465 485);
PAINT MONO (2465 485);
FORCEPROP 0 LASTPIN (2475 425) $PN 4
J 2
(2465 435);
DISPLAY 0.680851 (2465 435);
PAINT MONO (2465 435);
FORCEPROP 0 LASTPIN (3275 225) $PN TH
J 0
(3285 235);
DISPLAY 0.680851 (3285 235);
PAINT MONO (3285 235);
FORCEPROP 0 LASTPIN (2475 725) $PN 9
J 2
(2465 735);
DISPLAY 0.680851 (2465 735);
PAINT MONO (2465 735);
FORCEPROP 2 LAST CDS_LIB pure_quanta
J 0
(2875 475);
DISPLAY INVISIBLE (2875 475);
FORCEPROP 1 LAST CDS_LMAN_SYM_OUTLINE -250,300,250,-300
J 0
(2875 475);
DISPLAY 0.468085 (2875 475);
PAINT GREEN (2875 475);
DISPLAY INVISIBLE (2875 475);
FORCEPROP 1 LAST PATH I129
J 0
(2875 475);
DISPLAY 0.723404 (2875 475);
PAINT GREEN (2875 475);
DISPLAY INVISIBLE (2875 475);
FORCEPROP 1 LAST NEEDS_NO_SIZE TRUE
J 0
(2875 475);
DISPLAY 0.723404 (2875 475);
PAINT GREEN (2875 475);
DISPLAY INVISIBLE (2875 475);
FORCEPROP 0 LAST CDS_LOCATION U276
J 0
(2600 1200);
DISPLAY 1.021277 (2600 1200);
DISPLAY INVISIBLE (2600 1200);
FORCEPROP 0 LAST $SEC 1
J 0
(2600 1200);
DISPLAY 0.680851 (2600 1200);
PAINT MONO (2600 1200);
DISPLAY INVISIBLE (2600 1200);
FORCEPROP 0 LAST CDS_SEC 1
J 0
(2600 1200);
DISPLAY 1.021277 (2600 1200);
DISPLAY INVISIBLE (2600 1200);
FORCEADD Q_RES..1
(1275 475);
FORCEPROP 1 LAST PART_NUMBER CS03322FB03
J 0
(1125 525);
DISPLAY 0.510638 (1125 525);
DISPLAY INVISIBLE (1125 525);
FORCEPROP 1 LAST MATERIAL CHIP
J 0
(1575 475);
DISPLAY 0.510638 (1575 475);
FORCEPROP 1 LAST WATTAGE 1/16W
J 2
(1400 875);
DISPLAY 0.510638 (1400 875);
FORCEPROP 1 LAST PACK_TYPE 0402LF
J 0
(1125 875);
DISPLAY 0.510638 (1125 875);
FORCEPROP 1 LAST TOLERANCE 1%
J 0
(1500 475);
DISPLAY 0.510638 (1500 475);
FORCEPROP 1 LAST VALUE 33.2
J 2
(1475 475);
DISPLAY 0.510638 (1475 475);
FORCEPROP 1 LAST $LOCATION R3754
J 0
(1025 475);
DISPLAY 0.787234 (1025 475);
FORCEPROP 1 LASTPIN (1175 475) $PN 1
J 0
(1187 487);
DISPLAY 0.787234 (1187 487);
FORCEPROP 1 LASTPIN (1375 475) $PN 2
J 0
(1337 487);
DISPLAY 0.787234 (1337 487);
FORCEPROP 2 LAST CDS_LIB pure_quanta
J 0
(1275 475);
PAINT MONO (1275 475);
DISPLAY INVISIBLE (1275 475);
FORCEPROP 1 LAST PATH I130
J 0
(1225 625);
DISPLAY 0.978723 (1225 625);
PAINT WHITE (1225 625);
DISPLAY INVISIBLE (1225 625);
FORCEPROP 2 LAST CDS_LOCATION R3754
J 0
(1225 675);
DISPLAY 1.021277 (1225 675);
DISPLAY INVISIBLE (1225 675);
FORCEPROP 2 LAST $SEC 1
J 0
(1225 675);
DISPLAY 0.680851 (1225 675);
PAINT MONO (1225 675);
DISPLAY INVISIBLE (1225 675);
FORCEPROP 2 LAST CDS_SEC 1
J 0
(1225 675);
DISPLAY 1.021277 (1225 675);
DISPLAY INVISIBLE (1225 675);
FORCEADD Q_RES..1
(1275 425);
FORCEPROP 1 LAST PART_NUMBER CS03322FB03
J 0
(1150 475);
DISPLAY 0.638298 (1150 475);
DISPLAY INVISIBLE (1150 475);
FORCEPROP 1 LAST VALUE 33.2
J 2
(1475 425);
DISPLAY 0.510638 (1475 425);
FORCEPROP 1 LAST TOLERANCE 1%
J 0
(1500 425);
DISPLAY 0.510638 (1500 425);
FORCEPROP 1 LAST MATERIAL CHIP
J 0
(1575 425);
DISPLAY 0.510638 (1575 425);
FORCEPROP 1 LAST $LOCATION R3756
J 0
(1025 425);
DISPLAY 0.787234 (1025 425);
FORCEPROP 1 LASTPIN (1175 425) $PN 1
J 0
(1187 437);
DISPLAY 0.787234 (1187 437);
FORCEPROP 1 LASTPIN (1375 425) $PN 2
J 0
(1337 437);
DISPLAY 0.787234 (1337 437);
FORCEPROP 2 LAST CDS_LIB pure_quanta
J 0
(1275 425);
PAINT MONO (1275 425);
DISPLAY INVISIBLE (1275 425);
FORCEPROP 1 LAST PACK_TYPE 0402LF
J 0
(1625 425);
DISPLAY 0.638298 (1625 425);
DISPLAY INVISIBLE (1625 425);
FORCEPROP 1 LAST WATTAGE 1/16W
J 2
(1475 525);
DISPLAY 0.638298 (1475 525);
DISPLAY INVISIBLE (1475 525);
FORCEPROP 1 LAST PATH I131
J 0
(1225 575);
DISPLAY 0.978723 (1225 575);
PAINT WHITE (1225 575);
DISPLAY INVISIBLE (1225 575);
FORCEPROP 2 LAST CDS_LOCATION R3756
J 0
(1225 625);
DISPLAY 1.021277 (1225 625);
DISPLAY INVISIBLE (1225 625);
FORCEPROP 2 LAST $SEC 1
J 0
(1225 625);
DISPLAY 0.680851 (1225 625);
PAINT MONO (1225 625);
DISPLAY INVISIBLE (1225 625);
FORCEPROP 2 LAST CDS_SEC 1
J 0
(1225 625);
DISPLAY 1.021277 (1225 625);
DISPLAY INVISIBLE (1225 625);
FORCEADD Q_RES..1
(1300 -125);
FORCEPROP 1 LAST PART_NUMBER CS01002FB07
J 0
(1150 -75);
DISPLAY 0.638298 (1150 -75);
DISPLAY INVISIBLE (1150 -75);
FORCEPROP 1 LAST MATERIAL CHIP
J 0
(1325 -225);
DISPLAY 0.638298 (1325 -225);
FORCEPROP 1 LAST VALUE 10
J 2
(1250 -175);
DISPLAY 0.638298 (1250 -175);
FORCEPROP 1 LAST TOLERANCE 1%
J 0
(1350 -175);
DISPLAY 0.638298 (1350 -175);
FORCEPROP 1 LAST PACK_TYPE 0402LF
J 0
(1425 -175);
DISPLAY 0.638298 (1425 -175);
FORCEPROP 1 LAST WATTAGE 1/16W
J 2
(1300 -225);
DISPLAY 0.638298 (1300 -225);
FORCEPROP 1 LAST $LOCATION R3758
J 0
(1050 -125);
DISPLAY 0.638298 (1050 -125);
FORCEPROP 1 LASTPIN (1200 -125) $PN 1
J 0
(1212 -113);
DISPLAY 0.787234 (1212 -113);
PAINT MONO (1212 -113);
FORCEPROP 1 LASTPIN (1400 -125) $PN 2
J 0
(1362 -113);
DISPLAY 0.787234 (1362 -113);
PAINT MONO (1362 -113);
FORCEPROP 2 LAST CDS_LIB pure_quanta
J 0
(1300 -125);
DISPLAY INVISIBLE (1300 -125);
FORCEPROP 1 LAST PATH I132
J 0
(1250 25);
DISPLAY 0.978723 (1250 25);
PAINT WHITE (1250 25);
DISPLAY INVISIBLE (1250 25);
FORCEPROP 0 LAST CDS_LOCATION R3758
J 0
(1150 -25);
DISPLAY 1.021277 (1150 -25);
DISPLAY INVISIBLE (1150 -25);
FORCEPROP 0 LAST $SEC 1
J 0
(1150 -25);
DISPLAY 0.680851 (1150 -25);
PAINT MONO (1150 -25);
DISPLAY INVISIBLE (1150 -25);
FORCEPROP 0 LAST CDS_SEC 1
J 0
(1150 -25);
DISPLAY 1.021277 (1150 -25);
DISPLAY INVISIBLE (1150 -25);
FORCEADD Q_CAP..1
(1650 -275);
FORCEPROP 1 LAST PART_NUMBER CH4104K1B00
J 0
(1700 -325);
DISPLAY 0.510638 (1700 -325);
DISPLAY INVISIBLE (1700 -325);
FORCEPROP 1 LAST PACK_TYPE 0402
J 0
(1700 -350);
DISPLAY 0.510638 (1700 -350);
FORCEPROP 1 LAST VALUE 0.1UF
J 0
(1700 -225);
DISPLAY 0.510638 (1700 -225);
FORCEPROP 1 LAST MATERIAL X7R
J 0
(1700 -300);
DISPLAY 0.510638 (1700 -300);
FORCEPROP 1 LAST TOLERANCE 10%
J 0
(1700 -275);
DISPLAY 0.510638 (1700 -275);
FORCEPROP 1 LAST VOLTAGE 25V
J 0
(1700 -250);
DISPLAY 0.510638 (1700 -250);
FORCEPROP 1 LAST $LOCATION C2071
J 0
(1700 -175);
DISPLAY 0.978723 (1700 -175);
FORCEPROP 1 LASTPIN (1650 -175) $PN 1
J 0
(1660 -195);
DISPLAY 0.787234 (1660 -195);
PAINT MONO (1660 -195);
FORCEPROP 1 LASTPIN (1650 -375) $PN 2
J 0
(1660 -395);
DISPLAY 0.787234 (1660 -395);
PAINT MONO (1660 -395);
FORCEPROP 2 LAST CDS_LIB pure_quanta
J 0
(1650 -275);
DISPLAY INVISIBLE (1650 -275);
FORCEPROP 1 LAST PATH I133
J 0
(1700 -125);
DISPLAY 0.978723 (1700 -125);
PAINT WHITE (1700 -125);
DISPLAY INVISIBLE (1700 -125);
FORCEPROP 0 LAST CDS_LOCATION C2071
J 0
(1700 -125);
DISPLAY 1.021277 (1700 -125);
DISPLAY INVISIBLE (1700 -125);
FORCEPROP 0 LAST $SEC 1
J 0
(1700 -125);
DISPLAY 0.680851 (1700 -125);
PAINT MONO (1700 -125);
DISPLAY INVISIBLE (1700 -125);
FORCEPROP 0 LAST CDS_SEC 1
J 0
(1700 -125);
DISPLAY 1.021277 (1700 -125);
DISPLAY INVISIBLE (1700 -125);
FORCEADD Q_RES..1
(1300 -400);
FORCEPROP 1 LAST PART_NUMBER CS01002FB07
J 0
(1150 -350);
DISPLAY 0.638298 (1150 -350);
DISPLAY INVISIBLE (1150 -350);
FORCEPROP 1 LAST MATERIAL CHIP
J 0
(1325 -500);
DISPLAY 0.638298 (1325 -500);
FORCEPROP 1 LAST WATTAGE 1/16W
J 2
(1300 -500);
DISPLAY 0.638298 (1300 -500);
FORCEPROP 1 LAST PACK_TYPE 0402LF
J 0
(1425 -450);
DISPLAY 0.638298 (1425 -450);
FORCEPROP 1 LAST TOLERANCE 1%
J 0
(1350 -450);
DISPLAY 0.638298 (1350 -450);
FORCEPROP 1 LAST VALUE 10
J 2
(1250 -450);
DISPLAY 0.638298 (1250 -450);
FORCEPROP 1 LAST $LOCATION R3760
J 0
(1050 -400);
DISPLAY 0.638298 (1050 -400);
FORCEPROP 1 LASTPIN (1200 -400) $PN 1
J 0
(1212 -388);
DISPLAY 0.787234 (1212 -388);
PAINT MONO (1212 -388);
FORCEPROP 1 LASTPIN (1400 -400) $PN 2
J 0
(1362 -388);
DISPLAY 0.787234 (1362 -388);
PAINT MONO (1362 -388);
FORCEPROP 2 LAST CDS_LIB pure_quanta
J 0
(1300 -400);
DISPLAY INVISIBLE (1300 -400);
FORCEPROP 1 LAST PATH I134
J 0
(1250 -250);
DISPLAY 0.978723 (1250 -250);
PAINT WHITE (1250 -250);
DISPLAY INVISIBLE (1250 -250);
FORCEPROP 0 LAST CDS_LOCATION R3760
J 0
(1150 -300);
DISPLAY 1.021277 (1150 -300);
DISPLAY INVISIBLE (1150 -300);
FORCEPROP 0 LAST $SEC 1
J 0
(1150 -300);
DISPLAY 0.680851 (1150 -300);
PAINT MONO (1150 -300);
DISPLAY INVISIBLE (1150 -300);
FORCEPROP 0 LAST CDS_SEC 1
J 0
(1150 -300);
DISPLAY 1.021277 (1150 -300);
DISPLAY INVISIBLE (1150 -300);
FORCEADD Q_RES..1
(750 1000);
FORCEPROP 1 LAST PART_NUMBER CS24702FB06
J 0
(250 1000);
DISPLAY 0.510638 (250 1000);
DISPLAY INVISIBLE (250 1000);
FORCEPROP 1 LAST VALUE 4.7K
J 2
(950 1000);
DISPLAY 0.510638 (950 1000);
FORCEPROP 1 LAST WATTAGE 1/16W
J 2
(1075 1000);
DISPLAY 0.510638 (1075 1000);
FORCEPROP 1 LAST MATERIAL EMPTY
J 0
(1125 1000);
DISPLAY 0.510638 (1125 1000);
PAINT RED (1125 1000);
FORCEPROP 1 LAST PACK_TYPE 0402LF
J 0
(1250 1000);
DISPLAY 0.510638 (1250 1000);
FORCEPROP 1 LAST TOLERANCE 1%
J 0
(1075 1000);
DISPLAY 0.510638 (1075 1000);
FORCEPROP 1 LAST $LOCATION R3764
J 0
(550 1000);
DISPLAY 0.638298 (550 1000);
FORCEPROP 1 LASTPIN (650 1000) $PN 1
J 0
(662 1012);
DISPLAY 0.787234 (662 1012);
PAINT MONO (662 1012);
FORCEPROP 1 LASTPIN (850 1000) $PN 2
J 0
(812 1012);
DISPLAY 0.787234 (812 1012);
PAINT MONO (812 1012);
FORCEPROP 1 LAST PATH I135
J 0
(700 1150);
DISPLAY 0.978723 (700 1150);
PAINT WHITE (700 1150);
DISPLAY INVISIBLE (700 1150);
FORCEPROP 2 LAST CDS_LIB pure_quanta
J 0
(750 1000);
DISPLAY INVISIBLE (750 1000);
FORCEPROP 0 LAST CDS_LOCATION R3764
J 0
(625 1050);
DISPLAY 1.021277 (625 1050);
DISPLAY INVISIBLE (625 1050);
FORCEPROP 0 LAST $SEC 1
J 0
(625 1050);
DISPLAY 0.680851 (625 1050);
PAINT MONO (625 1050);
DISPLAY INVISIBLE (625 1050);
FORCEPROP 0 LAST CDS_SEC 1
J 0
(625 1050);
DISPLAY 1.021277 (625 1050);
DISPLAY INVISIBLE (625 1050);
FORCEADD Q_RES..1
(750 1075);
FORCEPROP 1 LAST PART_NUMBER CS24702FB06
J 0
(250 1075);
DISPLAY 0.510638 (250 1075);
DISPLAY INVISIBLE (250 1075);
FORCEPROP 1 LAST MATERIAL CHIP
J 0
(1125 1075);
DISPLAY 0.510638 (1125 1075);
FORCEPROP 1 LAST TOLERANCE 1%
J 0
(1075 1075);
DISPLAY 0.510638 (1075 1075);
FORCEPROP 1 LAST WATTAGE 1/16W
J 2
(1075 1075);
DISPLAY 0.510638 (1075 1075);
FORCEPROP 1 LAST VALUE 4.7K
J 2
(950 1075);
DISPLAY 0.510638 (950 1075);
FORCEPROP 1 LAST PACK_TYPE 0402LF
J 0
(1250 1075);
DISPLAY 0.510638 (1250 1075);
FORCEPROP 1 LAST $LOCATION R3763
J 0
(550 1075);
DISPLAY 0.638298 (550 1075);
FORCEPROP 1 LASTPIN (650 1075) $PN 1
J 0
(662 1087);
DISPLAY 0.787234 (662 1087);
PAINT MONO (662 1087);
FORCEPROP 1 LASTPIN (850 1075) $PN 2
J 0
(812 1087);
DISPLAY 0.787234 (812 1087);
PAINT MONO (812 1087);
FORCEPROP 1 LAST PATH I136
J 0
(700 1225);
DISPLAY 0.978723 (700 1225);
PAINT WHITE (700 1225);
DISPLAY INVISIBLE (700 1225);
FORCEPROP 2 LAST CDS_LIB pure_quanta
J 0
(750 1075);
DISPLAY INVISIBLE (750 1075);
FORCEPROP 0 LAST CDS_LOCATION R3763
J 0
(625 1125);
DISPLAY 1.021277 (625 1125);
DISPLAY INVISIBLE (625 1125);
FORCEPROP 0 LAST $SEC 1
J 0
(625 1125);
DISPLAY 0.680851 (625 1125);
PAINT MONO (625 1125);
DISPLAY INVISIBLE (625 1125);
FORCEPROP 0 LAST CDS_SEC 1
J 0
(625 1125);
DISPLAY 1.021277 (625 1125);
DISPLAY INVISIBLE (625 1125);
FORCEADD UNIVERSAL_GND..1
(175 875);
FORCEPROP 3 LASTPIN (175 925) SIG_NAME GND\g
J 0
(185 935);
DISPLAY 0.659574 (185 935);
PAINT MONO (185 935);
DISPLAY INVISIBLE (185 935);
FORCEPROP 1 LAST PATH I137
J 0
(250 875);
DISPLAY 0.872340 (250 875);
PAINT AQUA (250 875);
DISPLAY INVISIBLE (250 875);
FORCEPROP 1 LAST HDL_POWER GND
J 1
(200 800);
DISPLAY 0.872340 (200 800);
PAINT GREEN (200 800);
DISPLAY INVISIBLE (200 800);
FORCEPROP 2 LAST CDS_LIB logical_power
J 0
(175 875);
DISPLAY INVISIBLE (175 875);
FORCEADD OFFPAGE..1
(75 475);
FORCEPROP 2 LAST $XR0 232 
J 0
(-177 475);
DISPLAY 0.638298 (-177 475);
PAINT MONO (-177 475);
FORCEPROP 2 LAST CDS_LIB standard
J 0
(75 475);
DISPLAY INVISIBLE (75 475);
FORCEPROP 1 LAST OFFPAGE TRUE
J 0
(400 350);
DISPLAY 0.872340 (400 350);
DISPLAY INVISIBLE (400 350);
FORCEPROP 1 LAST COMMENT_BODY TRUE
J 0
(200 375);
DISPLAY 0.872340 (200 375);
PAINT GREEN (200 375);
DISPLAY INVISIBLE (200 375);
FORCEPROP 2 LAST PATH I138
J 0
(-175 525);
DISPLAY 1.021277 (-175 525);
DISPLAY INVISIBLE (-175 525);
FORCEADD OFFPAGE..3
R 2
(75 425);
FORCEPROP 2 LAST $XR0 232 
J 0
(-205 425);
DISPLAY 0.638298 (-205 425);
PAINT MONO (-205 425);
FORCEPROP 1 LAST OFFPAGE TRUE
J 2
(-250 300);
DISPLAY 0.872340 (-250 300);
DISPLAY INVISIBLE (-250 300);
FORCEPROP 1 LAST COMMENT_BODY TRUE
J 2
(125 325);
DISPLAY 0.872340 (125 325);
PAINT GREEN (125 325);
DISPLAY INVISIBLE (125 325);
FORCEPROP 2 LAST CDS_LIB standard
J 2
(75 425);
PAINT MONO (75 425);
DISPLAY INVISIBLE (75 425);
FORCEPROP 2 LAST PATH I139
J 0
(-200 475);
DISPLAY 1.021277 (-200 475);
DISPLAY INVISIBLE (-200 475);
FORCEADD UNIVERSAL_POWER..1
(-100 225);
FORCEPROP 3 LASTPIN (-100 175) SIG_NAME P3V3_E1S_0_R\g
J 0
(-90 185);
DISPLAY 0.659574 (-90 185);
PAINT MONO (-90 185);
DISPLAY INVISIBLE (-90 185);
FORCEPROP 1 LAST HDL_POWER P3V3_E1S_0_R
J 1
(-100 275);
DISPLAY 0.872340 (-100 275);
PAINT GREEN (-100 275);
FORCEPROP 1 LAST PATH I140
J 0
(-50 250);
DISPLAY 0.872340 (-50 250);
PAINT AQUA (-50 250);
DISPLAY INVISIBLE (-50 250);
FORCEPROP 2 LAST CDS_LIB logical_power
J 0
(-100 225);
DISPLAY INVISIBLE (-100 225);
FORCEADD Q_CAP..1
(-500 650);
FORCEPROP 1 LAST PART_NUMBER CH4104K1B00
J 0
(-450 500);
DISPLAY 0.808511 (-450 500);
DISPLAY INVISIBLE (-450 500);
FORCEPROP 1 LAST VALUE 0.1UF
J 0
(-450 700);
DISPLAY 0.638298 (-450 700);
FORCEPROP 1 LAST PACK_TYPE 0402
J 0
(-450 500);
DISPLAY 0.638298 (-450 500);
FORCEPROP 1 LAST TOLERANCE 10%
J 0
(-450 600);
DISPLAY 0.638298 (-450 600);
FORCEPROP 1 LAST VOLTAGE 25V
J 0
(-450 650);
DISPLAY 0.638298 (-450 650);
FORCEPROP 1 LAST MATERIAL X7R
J 0
(-450 550);
DISPLAY 0.638298 (-450 550);
FORCEPROP 1 LAST $LOCATION C2069
J 0
(-450 750);
DISPLAY 0.978723 (-450 750);
FORCEPROP 1 LASTPIN (-500 750) $PN 1
J 0
(-490 730);
DISPLAY 0.787234 (-490 730);
PAINT MONO (-490 730);
FORCEPROP 1 LASTPIN (-500 550) $PN 2
J 0
(-490 530);
DISPLAY 0.787234 (-490 530);
PAINT MONO (-490 530);
FORCEPROP 2 LAST CDS_LIB pure_quanta
J 0
(-500 650);
DISPLAY INVISIBLE (-500 650);
FORCEPROP 1 LAST PATH I142
J 0
(-450 800);
DISPLAY 0.978723 (-450 800);
PAINT WHITE (-450 800);
DISPLAY INVISIBLE (-450 800);
FORCEPROP 0 LAST CDS_LOCATION C2069
J 0
(-450 800);
DISPLAY 1.021277 (-450 800);
DISPLAY INVISIBLE (-450 800);
FORCEPROP 0 LAST $SEC 1
J 0
(-450 800);
DISPLAY 0.680851 (-450 800);
PAINT MONO (-450 800);
DISPLAY INVISIBLE (-450 800);
FORCEPROP 0 LAST CDS_SEC 1
J 0
(-450 800);
DISPLAY 1.021277 (-450 800);
DISPLAY INVISIBLE (-450 800);
FORCEADD UNIVERSAL_GND..1
(-500 375);
FORCEPROP 3 LASTPIN (-500 425) SIG_NAME GND\g
J 0
(-490 435);
DISPLAY 0.659574 (-490 435);
PAINT MONO (-490 435);
DISPLAY INVISIBLE (-490 435);
FORCEPROP 2 LAST CDS_LIB logical_power
J 0
(-500 375);
DISPLAY INVISIBLE (-500 375);
FORCEPROP 1 LAST HDL_POWER GND
J 1
(-475 300);
DISPLAY 0.872340 (-475 300);
PAINT GREEN (-475 300);
DISPLAY INVISIBLE (-475 300);
FORCEPROP 1 LAST PATH I143
J 0
(-425 375);
DISPLAY 0.872340 (-425 375);
PAINT AQUA (-425 375);
DISPLAY INVISIBLE (-425 375);
FORCEADD UNIVERSAL_POWER..1
(-1175 225);
FORCEPROP 3 LASTPIN (-1175 175) SIG_NAME P3V3_E1S_0\g
J 0
(-1165 185);
DISPLAY 0.659574 (-1165 185);
PAINT MONO (-1165 185);
DISPLAY INVISIBLE (-1165 185);
FORCEPROP 1 LAST HDL_POWER P3V3_E1S_0
J 1
(-1175 275);
DISPLAY 0.872340 (-1175 275);
PAINT GREEN (-1175 275);
FORCEPROP 2 LAST CDS_LIB logical_power
J 0
(-1175 225);
DISPLAY INVISIBLE (-1175 225);
FORCEPROP 1 LAST PATH I145
J 0
(-1125 250);
DISPLAY 0.872340 (-1125 250);
PAINT AQUA (-1125 250);
DISPLAY INVISIBLE (-1125 250);
FORCEADD Q_RES..2
(1550 825);
FORCEPROP 1 LAST PART_NUMBER CS00002JB13
J 0
(1625 775);
DISPLAY 0.404255 (1625 775);
DISPLAY INVISIBLE (1625 775);
FORCEPROP 1 LAST PACK_TYPE 0402LF
J 0
(1625 750);
DISPLAY 0.404255 (1625 750);
FORCEPROP 1 LAST WATTAGE 1/16W
J 0
(1625 825);
DISPLAY 0.404255 (1625 825);
FORCEPROP 1 LAST TOLERANCE 5%
J 0
(1625 850);
DISPLAY 0.404255 (1625 850);
FORCEPROP 1 LAST MATERIAL CHIP
J 0
(1625 800);
DISPLAY 0.404255 (1625 800);
FORCEPROP 1 LAST VALUE 0
J 0
(1625 875);
DISPLAY 0.404255 (1625 875);
FORCEPROP 1 LAST $LOCATION R3751
J 0
(1625 900);
DISPLAY 0.978723 (1625 900);
FORCEPROP 1 LASTPIN (1550 925) $PN 1
J 0
(1555 887);
DISPLAY 0.787234 (1555 887);
PAINT MONO (1555 887);
FORCEPROP 1 LASTPIN (1550 725) $PN 2
J 0
(1555 735);
DISPLAY 0.787234 (1555 735);
PAINT MONO (1555 735);
FORCEPROP 1 LAST PATH I146
J 0
(1600 1000);
DISPLAY 0.978723 (1600 1000);
PAINT WHITE (1600 1000);
DISPLAY INVISIBLE (1600 1000);
FORCEPROP 2 LAST CDS_LIB pure_quanta
J 0
(1550 825);
DISPLAY INVISIBLE (1550 825);
FORCEPROP 0 LAST CDS_LOCATION R3751
J 0
(1625 950);
DISPLAY 1.021277 (1625 950);
DISPLAY INVISIBLE (1625 950);
FORCEPROP 0 LAST $SEC 1
J 0
(1625 950);
DISPLAY 0.680851 (1625 950);
PAINT MONO (1625 950);
DISPLAY INVISIBLE (1625 950);
FORCEPROP 0 LAST CDS_SEC 1
J 0
(1625 950);
DISPLAY 1.021277 (1625 950);
DISPLAY INVISIBLE (1625 950);
FORCEADD UNIVERSAL_POWER..1
(-250 975);
FORCEPROP 3 LASTPIN (-250 925) SIG_NAME P3V3_E1S_0_R\g
J 0
(-240 935);
DISPLAY 0.659574 (-240 935);
PAINT MONO (-240 935);
DISPLAY INVISIBLE (-240 935);
FORCEPROP 1 LAST HDL_POWER P3V3_E1S_0_R
J 1
(-250 1025);
DISPLAY 0.872340 (-250 1025);
PAINT GREEN (-250 1025);
FORCEPROP 2 LAST CDS_LIB logical_power
J 0
(-250 975);
DISPLAY INVISIBLE (-250 975);
FORCEPROP 1 LAST PATH I147
J 0
(-200 1000);
DISPLAY 0.872340 (-200 1000);
PAINT AQUA (-200 1000);
DISPLAY INVISIBLE (-200 1000);
FORCEADD UNIVERSAL_POWER..1
(4125 1375);
FORCEPROP 3 LASTPIN (4125 1325) SIG_NAME P3V3_AUX\g
J 0
(4135 1335);
DISPLAY 0.659574 (4135 1335);
PAINT MONO (4135 1335);
DISPLAY INVISIBLE (4135 1335);
FORCEPROP 1 LAST HDL_POWER P3V3_AUX
J 1
(4125 1425);
DISPLAY 0.872340 (4125 1425);
PAINT GREEN (4125 1425);
FORCEPROP 2 LAST CDS_LIB logical_power
J 0
(4125 1375);
DISPLAY INVISIBLE (4125 1375);
FORCEPROP 1 LAST PATH I148
J 0
(4175 1400);
DISPLAY 0.872340 (4175 1400);
PAINT AQUA (4175 1400);
DISPLAY INVISIBLE (4175 1400);
FORCEADD Q_RES..2
(4125 1175);
FORCEPROP 1 LAST PART_NUMBER CS24702FB06
J 0
(4165 1050);
DISPLAY 0.787234 (4165 1050);
DISPLAY INVISIBLE (4165 1050);
FORCEPROP 1 LAST VALUE 4.7K
J 0
(4170 1250);
DISPLAY 0.787234 (4170 1250);
FORCEPROP 1 LAST TOLERANCE 1%
J 0
(4170 1200);
DISPLAY 0.787234 (4170 1200);
FORCEPROP 1 LAST WATTAGE 1/16W
J 0
(4165 1150);
DISPLAY 0.787234 (4165 1150);
FORCEPROP 1 LAST MATERIAL CHIP
J 0
(4165 1100);
DISPLAY 0.787234 (4165 1100);
FORCEPROP 1 LAST PACK_TYPE 0402LF
J 0
(4165 1000);
DISPLAY 0.787234 (4165 1000);
FORCEPROP 1 LAST $LOCATION R4093
J 0
(4170 1300);
DISPLAY 0.978723 (4170 1300);
FORCEPROP 1 LASTPIN (4125 1275) $PN 1
J 0
(4130 1237);
DISPLAY 0.787234 (4130 1237);
PAINT MONO (4130 1237);
FORCEPROP 1 LASTPIN (4125 1075) $PN 2
J 0
(4130 1085);
DISPLAY 0.787234 (4130 1085);
PAINT MONO (4130 1085);
FORCEPROP 2 LAST CDS_LIB pure_quanta
J 0
(4125 1175);
DISPLAY INVISIBLE (4125 1175);
FORCEPROP 1 LAST PATH I149
J 0
(4175 1350);
DISPLAY 0.978723 (4175 1350);
PAINT WHITE (4175 1350);
DISPLAY INVISIBLE (4175 1350);
FORCEPROP 0 LAST CDS_LOCATION R4093
J 0
(4175 1350);
DISPLAY 1.021277 (4175 1350);
DISPLAY INVISIBLE (4175 1350);
FORCEPROP 0 LAST $SEC 1
J 0
(4175 1350);
DISPLAY 0.680851 (4175 1350);
PAINT MONO (4175 1350);
DISPLAY INVISIBLE (4175 1350);
FORCEPROP 0 LAST CDS_SEC 1
J 0
(4175 1350);
DISPLAY 1.021277 (4175 1350);
DISPLAY INVISIBLE (4175 1350);
FORCEADD UNIVERSAL_POWER..1
(4150 3975);
FORCEPROP 3 LASTPIN (4150 3925) SIG_NAME P3V3_AUX\g
J 0
(4160 3935);
DISPLAY 0.659574 (4160 3935);
PAINT MONO (4160 3935);
DISPLAY INVISIBLE (4160 3935);
FORCEPROP 1 LAST HDL_POWER P3V3_AUX
J 1
(4150 4025);
DISPLAY 0.872340 (4150 4025);
PAINT GREEN (4150 4025);
FORCEPROP 2 LAST CDS_LIB logical_power
J 0
(4150 3975);
DISPLAY INVISIBLE (4150 3975);
FORCEPROP 1 LAST PATH I150
J 0
(4200 4000);
DISPLAY 0.872340 (4200 4000);
PAINT AQUA (4200 4000);
DISPLAY INVISIBLE (4200 4000);
FORCEADD Q_RES..2
(4150 3775);
FORCEPROP 1 LAST PART_NUMBER CS24702FB06
J 0
(4190 3650);
DISPLAY 0.787234 (4190 3650);
DISPLAY INVISIBLE (4190 3650);
FORCEPROP 1 LAST VALUE 4.7K
J 0
(4195 3850);
DISPLAY 0.787234 (4195 3850);
FORCEPROP 1 LAST PACK_TYPE 0402LF
J 0
(4190 3600);
DISPLAY 0.787234 (4190 3600);
FORCEPROP 1 LAST TOLERANCE 1%
J 0
(4195 3800);
DISPLAY 0.787234 (4195 3800);
FORCEPROP 1 LAST WATTAGE 1/16W
J 0
(4190 3750);
DISPLAY 0.787234 (4190 3750);
FORCEPROP 1 LAST MATERIAL CHIP
J 0
(4190 3700);
DISPLAY 0.787234 (4190 3700);
FORCEPROP 1 LAST $LOCATION R4094
J 0
(4195 3900);
DISPLAY 0.978723 (4195 3900);
FORCEPROP 1 LASTPIN (4150 3875) $PN 1
J 0
(4155 3837);
DISPLAY 0.787234 (4155 3837);
PAINT MONO (4155 3837);
FORCEPROP 1 LASTPIN (4150 3675) $PN 2
J 0
(4155 3685);
DISPLAY 0.787234 (4155 3685);
PAINT MONO (4155 3685);
FORCEPROP 2 LAST CDS_LIB pure_quanta
J 0
(4150 3775);
DISPLAY INVISIBLE (4150 3775);
FORCEPROP 1 LAST PATH I151
J 0
(4200 3950);
DISPLAY 0.978723 (4200 3950);
PAINT WHITE (4200 3950);
DISPLAY INVISIBLE (4200 3950);
FORCEPROP 0 LAST CDS_LOCATION R4094
J 0
(4200 3950);
DISPLAY 1.021277 (4200 3950);
DISPLAY INVISIBLE (4200 3950);
FORCEPROP 0 LAST $SEC 1
J 0
(4200 3950);
DISPLAY 0.680851 (4200 3950);
PAINT MONO (4200 3950);
DISPLAY INVISIBLE (4200 3950);
FORCEPROP 0 LAST CDS_SEC 1
J 0
(4200 3950);
DISPLAY 1.021277 (4200 3950);
DISPLAY INVISIBLE (4200 3950);
FORCEADD Q_RES..1
(-600 2675);
FORCEPROP 1 LAST PART_NUMBER CS+0108F128
J 0
(-750 2750);
DISPLAY 0.638298 (-750 2750);
DISPLAY INVISIBLE (-750 2750);
FORCEPROP 1 LAST VALUE 0.01
J 2
(-625 2575);
DISPLAY 0.638298 (-625 2575);
FORCEPROP 1 LAST TOLERANCE 1%
J 0
(-600 2575);
DISPLAY 0.638298 (-600 2575);
FORCEPROP 1 LAST MATERIAL CHIP
J 0
(-600 2525);
DISPLAY 0.638298 (-600 2525);
FORCEPROP 1 LAST WATTAGE 1W
J 2
(-625 2525);
DISPLAY 0.638298 (-625 2525);
FORCEPROP 1 LAST PACK_TYPE 2512LF
J 0
(-500 2575);
DISPLAY 0.638298 (-500 2575);
FORCEPROP 1 LAST LOCATION R3645
J 0
(-825 2675);
DISPLAY 0.638298 (-825 2675);
FORCEPROP 1 LASTPIN (-700 2675) $PN 1
J 0
(-688 2687);
DISPLAY 0.787234 (-688 2687);
PAINT MONO (-688 2687);
FORCEPROP 1 LASTPIN (-500 2675) $PN 2
J 0
(-538 2687);
DISPLAY 0.787234 (-538 2687);
PAINT MONO (-538 2687);
FORCEPROP 1 LAST PATH I152
J 0
(-650 2825);
DISPLAY 0.978723 (-650 2825);
PAINT WHITE (-650 2825);
DISPLAY INVISIBLE (-650 2825);
FORCEPROP 2 LAST CDS_LIB pure_quanta
J 0
(-600 2675);
DISPLAY INVISIBLE (-600 2675);
FORCEPROP 0 LAST $SEC 1
J 0
(-750 2800);
DISPLAY 0.680851 (-750 2800);
PAINT MONO (-750 2800);
DISPLAY INVISIBLE (-750 2800);
FORCEPROP 0 LAST CDS_SEC 1
J 0
(-750 2800);
DISPLAY 1.021277 (-750 2800);
DISPLAY INVISIBLE (-750 2800);
FORCEADD Q_RES..1
(-600 75);
FORCEPROP 1 LAST PART_NUMBER CS+0108F128
J 0
(-750 150);
DISPLAY 0.638298 (-750 150);
DISPLAY INVISIBLE (-750 150);
FORCEPROP 1 LAST PACK_TYPE 2512LF
J 0
(-500 -25);
DISPLAY 0.638298 (-500 -25);
FORCEPROP 1 LAST WATTAGE 1W
J 2
(-625 -75);
DISPLAY 0.638298 (-625 -75);
FORCEPROP 1 LAST VALUE 0.01
J 2
(-625 -25);
DISPLAY 0.638298 (-625 -25);
FORCEPROP 1 LAST TOLERANCE 1%
J 0
(-600 -25);
DISPLAY 0.638298 (-600 -25);
FORCEPROP 1 LAST MATERIAL CHIP
J 0
(-600 -75);
DISPLAY 0.638298 (-600 -75);
FORCEPROP 1 LAST LOCATION R3767
J 0
(-825 75);
DISPLAY 0.638298 (-825 75);
FORCEPROP 1 LASTPIN (-700 75) $PN 1
J 0
(-688 87);
DISPLAY 0.787234 (-688 87);
PAINT MONO (-688 87);
FORCEPROP 1 LASTPIN (-500 75) $PN 2
J 0
(-538 87);
DISPLAY 0.787234 (-538 87);
PAINT MONO (-538 87);
FORCEPROP 1 LAST PATH I153
J 0
(-650 225);
DISPLAY 0.978723 (-650 225);
PAINT WHITE (-650 225);
DISPLAY INVISIBLE (-650 225);
FORCEPROP 2 LAST CDS_LIB pure_quanta
J 0
(-600 75);
DISPLAY INVISIBLE (-600 75);
FORCEPROP 0 LAST $SEC 1
J 0
(-750 200);
DISPLAY 0.680851 (-750 200);
PAINT MONO (-750 200);
DISPLAY INVISIBLE (-750 200);
FORCEPROP 0 LAST CDS_SEC 1
J 0
(-750 200);
DISPLAY 1.021277 (-750 200);
DISPLAY INVISIBLE (-750 200);
FORCEADD INA230AIRGTR..1
(2875 3075);
FORCEPROP 1 LAST PART_NUMBER AL000230001
J 0
(2628 3511);
DISPLAY 0.723404 (2628 3511);
PAINT GREEN (2628 3511);
DISPLAY INVISIBLE (2628 3511);
FORCEPROP 2 LAST PART_TYPE SMLF
J 0
(2600 3750);
DISPLAY 1.021277 (2600 3750);
FORCEPROP 1 LAST MATERIAL IC
J 0
(2628 3384);
DISPLAY 0.723404 (2628 3384);
PAINT GREEN (2628 3384);
FORCEPROP 2 LAST VALUE INA230AIRGTR
J 0
(2600 3700);
DISPLAY 1.021277 (2600 3700);
FORCEPROP 1 LAST $LOCATION U266
J 0
(2628 3658);
DISPLAY 0.723404 (2628 3658);
PAINT GREEN (2628 3658);
FORCEPROP 0 LASTPIN (2475 3175) $PN 2
J 2
(2465 3185);
DISPLAY 0.680851 (2465 3185);
PAINT MONO (2465 3185);
FORCEPROP 0 LASTPIN (2475 3225) $PN 1
J 2
(2465 3235);
DISPLAY 0.680851 (2465 3235);
PAINT MONO (2465 3235);
FORCEPROP 0 LASTPIN (3275 3325) $PN 3
J 0
(3285 3335);
DISPLAY 0.680851 (3285 3335);
PAINT MONO (3285 3335);
FORCEPROP 0 LASTPIN (2475 2925) $PN 11
J 2
(2465 2935);
DISPLAY 0.680851 (2465 2935);
PAINT MONO (2465 2935);
FORCEPROP 0 LASTPIN (3275 2875) $PN 10
J 0
(3285 2885);
DISPLAY 0.680851 (3285 2885);
PAINT MONO (3285 2885);
FORCEPROP 0 LASTPIN (2475 2875) $PN 13
J 2
(2465 2885);
DISPLAY 0.680851 (2465 2885);
PAINT MONO (2465 2885);
FORCEPROP 0 LASTPIN (2475 2825) $PN 12
J 2
(2465 2835);
DISPLAY 0.680851 (2465 2835);
PAINT MONO (2465 2835);
FORCEPROP 0 LASTPIN (3275 3225) $PN 6
J 0
(3285 3235);
DISPLAY 0.680851 (3285 3235);
PAINT MONO (3285 3235);
FORCEPROP 0 LASTPIN (3275 3175) $PN 7
J 0
(3285 3185);
DISPLAY 0.680851 (3285 3185);
PAINT MONO (3285 3185);
FORCEPROP 0 LASTPIN (3275 3125) $PN 8
J 0
(3285 3135);
DISPLAY 0.680851 (3285 3135);
PAINT MONO (3285 3135);
FORCEPROP 0 LASTPIN (3275 3075) $PN 14
J 0
(3285 3085);
DISPLAY 0.680851 (3285 3085);
PAINT MONO (3285 3085);
FORCEPROP 0 LASTPIN (3275 3025) $PN 15
J 0
(3285 3035);
DISPLAY 0.680851 (3285 3035);
PAINT MONO (3285 3035);
FORCEPROP 0 LASTPIN (3275 2975) $PN 16
J 0
(3285 2985);
DISPLAY 0.680851 (3285 2985);
PAINT MONO (3285 2985);
FORCEPROP 0 LASTPIN (2475 3075) $PN 5
J 2
(2465 3085);
DISPLAY 0.680851 (2465 3085);
PAINT MONO (2465 3085);
FORCEPROP 0 LASTPIN (2475 3025) $PN 4
J 2
(2465 3035);
DISPLAY 0.680851 (2465 3035);
PAINT MONO (2465 3035);
FORCEPROP 0 LASTPIN (3275 2825) $PN TH
J 0
(3285 2835);
DISPLAY 0.680851 (3285 2835);
PAINT MONO (3285 2835);
FORCEPROP 0 LASTPIN (2475 3325) $PN 9
J 2
(2465 3335);
DISPLAY 0.680851 (2465 3335);
PAINT MONO (2465 3335);
FORCEPROP 2 LAST CDS_LIB pure_quanta
J 0
(2875 3075);
DISPLAY INVISIBLE (2875 3075);
FORCEPROP 1 LAST CDS_LMAN_SYM_OUTLINE -250,300,250,-300
J 0
(2875 3075);
DISPLAY 0.468085 (2875 3075);
PAINT GREEN (2875 3075);
DISPLAY INVISIBLE (2875 3075);
FORCEPROP 1 LAST PATH I30
J 0
(2875 3075);
DISPLAY 0.723404 (2875 3075);
PAINT GREEN (2875 3075);
DISPLAY INVISIBLE (2875 3075);
FORCEPROP 1 LAST NEEDS_NO_SIZE TRUE
J 0
(2875 3075);
DISPLAY 0.723404 (2875 3075);
PAINT GREEN (2875 3075);
DISPLAY INVISIBLE (2875 3075);
FORCEPROP 0 LAST CDS_LOCATION U266
J 0
(2600 3800);
DISPLAY 1.021277 (2600 3800);
DISPLAY INVISIBLE (2600 3800);
FORCEPROP 0 LAST $SEC 1
J 0
(2600 3800);
DISPLAY 0.680851 (2600 3800);
PAINT MONO (2600 3800);
DISPLAY INVISIBLE (2600 3800);
FORCEPROP 0 LAST CDS_SEC 1
J 0
(2600 3800);
DISPLAY 1.021277 (2600 3800);
DISPLAY INVISIBLE (2600 3800);
FORCEADD Q_RES..1
(625 3350);
FORCEPROP 1 LAST PART_NUMBER CS24702FB06
J 0
(200 3350);
DISPLAY 0.510638 (200 3350);
DISPLAY INVISIBLE (200 3350);
FORCEPROP 1 LAST WATTAGE 1/16W
J 2
(950 3350);
DISPLAY 0.510638 (950 3350);
FORCEPROP 1 LAST TOLERANCE 1%
J 0
(950 3350);
DISPLAY 0.510638 (950 3350);
FORCEPROP 1 LAST MATERIAL CHIP
J 0
(1000 3350);
DISPLAY 0.510638 (1000 3350);
FORCEPROP 1 LAST PACK_TYPE 0402LF
J 0
(1100 3350);
DISPLAY 0.510638 (1100 3350);
FORCEPROP 1 LAST VALUE 4.7K
J 2
(825 3350);
DISPLAY 0.510638 (825 3350);
FORCEPROP 1 LAST $LOCATION R3616
J 0
(500 3350);
DISPLAY 0.638298 (500 3350);
FORCEPROP 1 LASTPIN (525 3350) $PN 1
J 0
(537 3362);
DISPLAY 0.787234 (537 3362);
PAINT MONO (537 3362);
FORCEPROP 1 LASTPIN (725 3350) $PN 2
J 0
(687 3362);
DISPLAY 0.787234 (687 3362);
PAINT MONO (687 3362);
FORCEPROP 1 LAST PATH I31
J 0
(575 3500);
DISPLAY 0.978723 (575 3500);
PAINT WHITE (575 3500);
DISPLAY INVISIBLE (575 3500);
FORCEPROP 2 LAST CDS_LIB pure_quanta
J 0
(625 3350);
DISPLAY INVISIBLE (625 3350);
FORCEPROP 0 LAST CDS_LOCATION R3616
J 0
(500 3400);
DISPLAY 1.021277 (500 3400);
DISPLAY INVISIBLE (500 3400);
FORCEPROP 0 LAST $SEC 1
J 0
(500 3400);
DISPLAY 0.680851 (500 3400);
PAINT MONO (500 3400);
DISPLAY INVISIBLE (500 3400);
FORCEPROP 0 LAST CDS_SEC 1
J 0
(500 3400);
DISPLAY 1.021277 (500 3400);
DISPLAY INVISIBLE (500 3400);
FORCEADD OFFPAGE..2
(5550 3325);
FORCEPROP 2 LAST $XR0 214 
J 0
(5739 3325);
DISPLAY 0.638298 (5739 3325);
PAINT MONO (5739 3325);
FORCEPROP 2 LAST CDS_LIB standard
J 0
(5550 3325);
DISPLAY INVISIBLE (5550 3325);
FORCEPROP 2 LAST PATH I32
J 0
(5725 3400);
DISPLAY 1.021277 (5725 3400);
DISPLAY INVISIBLE (5725 3400);
FORCEPROP 1 LAST OFFPAGE TRUE
J 0
(5875 3200);
DISPLAY 0.872340 (5875 3200);
DISPLAY INVISIBLE (5875 3200);
FORCEPROP 1 LAST COMMENT_BODY TRUE
J 0
(5505 3230);
DISPLAY 0.872340 (5505 3230);
PAINT GREEN (5505 3230);
DISPLAY INVISIBLE (5505 3230);
FORCEADD UNIVERSAL_POWER..1
(2425 4075);
FORCEPROP 3 LASTPIN (2425 4025) SIG_NAME P3V3_AUX\g
J 0
(2435 4035);
DISPLAY 0.659574 (2435 4035);
PAINT MONO (2435 4035);
DISPLAY INVISIBLE (2435 4035);
FORCEPROP 1 LAST HDL_POWER P3V3_AUX
J 1
(2425 4125);
DISPLAY 0.872340 (2425 4125);
PAINT GREEN (2425 4125);
FORCEPROP 2 LAST CDS_LIB logical_power
J 0
(2425 4075);
DISPLAY INVISIBLE (2425 4075);
FORCEPROP 1 LAST PATH I33
J 0
(2475 4100);
DISPLAY 0.872340 (2475 4100);
PAINT AQUA (2475 4100);
DISPLAY INVISIBLE (2475 4100);
FORCEADD Q_CAP..1
(2175 3675);
FORCEPROP 1 LAST PART_NUMBER CH4104K1B00
J 0
(2225 3525);
DISPLAY 0.808511 (2225 3525);
DISPLAY INVISIBLE (2225 3525);
FORCEPROP 1 LAST TOLERANCE 10%
J 0
(2225 3625);
DISPLAY 0.638298 (2225 3625);
FORCEPROP 1 LAST PACK_TYPE 0402
J 0
(2225 3525);
DISPLAY 0.638298 (2225 3525);
FORCEPROP 1 LAST VOLTAGE 25V
J 0
(2225 3675);
DISPLAY 0.638298 (2225 3675);
FORCEPROP 1 LAST MATERIAL X7R
J 0
(2225 3575);
DISPLAY 0.638298 (2225 3575);
FORCEPROP 1 LAST VALUE 0.1UF
J 0
(2225 3725);
DISPLAY 0.638298 (2225 3725);
FORCEPROP 1 LAST $LOCATION C2015
J 0
(2225 3775);
DISPLAY 0.978723 (2225 3775);
FORCEPROP 1 LASTPIN (2175 3775) $PN 1
J 0
(2185 3755);
DISPLAY 0.787234 (2185 3755);
PAINT MONO (2185 3755);
FORCEPROP 1 LASTPIN (2175 3575) $PN 2
J 0
(2185 3555);
DISPLAY 0.787234 (2185 3555);
PAINT MONO (2185 3555);
FORCEPROP 2 LAST CDS_LIB pure_quanta
J 0
(2175 3675);
DISPLAY INVISIBLE (2175 3675);
FORCEPROP 1 LAST PATH I34
J 0
(2225 3825);
DISPLAY 0.978723 (2225 3825);
PAINT WHITE (2225 3825);
DISPLAY INVISIBLE (2225 3825);
FORCEPROP 0 LAST CDS_LOCATION C2015
J 0
(2225 3825);
DISPLAY 1.021277 (2225 3825);
DISPLAY INVISIBLE (2225 3825);
FORCEPROP 0 LAST $SEC 1
J 0
(2225 3825);
DISPLAY 0.680851 (2225 3825);
PAINT MONO (2225 3825);
DISPLAY INVISIBLE (2225 3825);
FORCEPROP 0 LAST CDS_SEC 1
J 0
(2225 3825);
DISPLAY 1.021277 (2225 3825);
DISPLAY INVISIBLE (2225 3825);
FORCEADD Q_RES..1
(4350 3325);
FORCEPROP 1 LAST PART_NUMBER CS00002JB13
J 0
(4075 3200);
DISPLAY 0.723404 (4075 3200);
PAINT WHITE (4075 3200);
DISPLAY INVISIBLE (4075 3200);
FORCEPROP 1 LAST MATERIAL CHIP
J 0
(4525 3325);
DISPLAY 0.574468 (4525 3325);
FORCEPROP 1 LAST VALUE 0
J 2
(4500 3325);
DISPLAY 0.574468 (4500 3325);
FORCEPROP 1 LAST PACK_TYPE 0402LF
J 0
(4650 3325);
DISPLAY 0.574468 (4650 3325);
FORCEPROP 1 LAST $LOCATION R3563
J 0
(4175 3325);
DISPLAY 0.510638 (4175 3325);
FORCEPROP 1 LASTPIN (4250 3325) $PN 1
J 0
(4262 3337);
DISPLAY 0.787234 (4262 3337);
PAINT MONO (4262 3337);
FORCEPROP 1 LASTPIN (4450 3325) $PN 2
J 0
(4412 3337);
DISPLAY 0.787234 (4412 3337);
PAINT MONO (4412 3337);
FORCEPROP 1 LAST WATTAGE 1/16W
J 2
(4425 3250);
DISPLAY 0.723404 (4425 3250);
PAINT SKYBLUE (4425 3250);
DISPLAY INVISIBLE (4425 3250);
FORCEPROP 1 LAST TOLERANCE 5%
J 0
(4150 3250);
DISPLAY 0.723404 (4150 3250);
PAINT SKYBLUE (4150 3250);
DISPLAY INVISIBLE (4150 3250);
FORCEPROP 2 LAST CDS_LIB pure_quanta
J 0
(4350 3325);
DISPLAY INVISIBLE (4350 3325);
FORCEPROP 1 LAST PATH I35
J 0
(4300 3475);
DISPLAY 0.978723 (4300 3475);
PAINT WHITE (4300 3475);
DISPLAY INVISIBLE (4300 3475);
FORCEPROP 0 LAST CDS_LOCATION R3563
J 0
(4650 3375);
DISPLAY 1.021277 (4650 3375);
DISPLAY INVISIBLE (4650 3375);
FORCEPROP 0 LAST $SEC 1
J 0
(4650 3375);
DISPLAY 0.680851 (4650 3375);
PAINT MONO (4650 3375);
DISPLAY INVISIBLE (4650 3375);
FORCEPROP 0 LAST CDS_SEC 1
J 0
(4650 3375);
DISPLAY 1.021277 (4650 3375);
DISPLAY INVISIBLE (4650 3375);
FORCEADD UNIVERSAL_GND..1
(3400 2425);
FORCEPROP 3 LASTPIN (3400 2475) SIG_NAME GND\g
J 0
(3410 2485);
DISPLAY 0.659574 (3410 2485);
PAINT MONO (3410 2485);
DISPLAY INVISIBLE (3410 2485);
FORCEPROP 1 LAST HDL_POWER GND
J 1
(3425 2350);
DISPLAY 0.872340 (3425 2350);
PAINT GREEN (3425 2350);
DISPLAY INVISIBLE (3425 2350);
FORCEPROP 2 LAST CDS_LIB logical_power
J 0
(3400 2425);
DISPLAY INVISIBLE (3400 2425);
FORCEPROP 1 LAST PATH I36
J 0
(3475 2425);
DISPLAY 0.872340 (3475 2425);
PAINT AQUA (3475 2425);
DISPLAY INVISIBLE (3475 2425);
FORCEADD UNIVERSAL_GND..1
(2175 3400);
FORCEPROP 3 LASTPIN (2175 3450) SIG_NAME GND\g
J 0
(2185 3460);
DISPLAY 0.659574 (2185 3460);
PAINT MONO (2185 3460);
DISPLAY INVISIBLE (2185 3460);
FORCEPROP 2 LAST CDS_LIB logical_power
J 0
(2175 3400);
DISPLAY INVISIBLE (2175 3400);
FORCEPROP 1 LAST HDL_POWER GND
J 1
(2200 3325);
DISPLAY 0.872340 (2200 3325);
PAINT GREEN (2200 3325);
DISPLAY INVISIBLE (2200 3325);
FORCEPROP 1 LAST PATH I37
J 0
(2250 3400);
DISPLAY 0.872340 (2250 3400);
PAINT AQUA (2250 3400);
DISPLAY INVISIBLE (2250 3400);
FORCEADD Q_RES..1
(1275 3075);
FORCEPROP 1 LAST PART_NUMBER CS03322FB03
J 0
(1125 3125);
DISPLAY 0.510638 (1125 3125);
DISPLAY INVISIBLE (1125 3125);
FORCEPROP 1 LAST MATERIAL CHIP
J 0
(1575 3075);
DISPLAY 0.510638 (1575 3075);
FORCEPROP 1 LAST TOLERANCE 1%
J 0
(1500 3075);
DISPLAY 0.510638 (1500 3075);
FORCEPROP 1 LAST VALUE 33.2
J 2
(1475 3075);
DISPLAY 0.510638 (1475 3075);
FORCEPROP 1 LAST PACK_TYPE 0402LF
J 0
(1125 3150);
DISPLAY 0.510638 (1125 3150);
FORCEPROP 1 LAST WATTAGE 1/16W
J 2
(1400 3150);
DISPLAY 0.510638 (1400 3150);
FORCEPROP 1 LAST $LOCATION R3600
J 0
(1025 3075);
DISPLAY 0.787234 (1025 3075);
FORCEPROP 1 LASTPIN (1175 3075) $PN 1
J 0
(1187 3087);
DISPLAY 0.787234 (1187 3087);
FORCEPROP 1 LASTPIN (1375 3075) $PN 2
J 0
(1337 3087);
DISPLAY 0.787234 (1337 3087);
FORCEPROP 2 LAST CDS_LIB pure_quanta
J 0
(1275 3075);
PAINT MONO (1275 3075);
DISPLAY INVISIBLE (1275 3075);
FORCEPROP 1 LAST PATH I38
J 0
(1225 3225);
DISPLAY 0.978723 (1225 3225);
PAINT WHITE (1225 3225);
DISPLAY INVISIBLE (1225 3225);
FORCEPROP 2 LAST CDS_LOCATION R3600
J 0
(1225 3275);
DISPLAY 1.021277 (1225 3275);
DISPLAY INVISIBLE (1225 3275);
FORCEPROP 2 LAST $SEC 1
J 0
(1225 3275);
DISPLAY 0.680851 (1225 3275);
PAINT MONO (1225 3275);
DISPLAY INVISIBLE (1225 3275);
FORCEPROP 2 LAST CDS_SEC 1
J 0
(1225 3275);
DISPLAY 1.021277 (1225 3275);
DISPLAY INVISIBLE (1225 3275);
FORCEADD Q_RES..1
(1275 3025);
FORCEPROP 1 LAST PART_NUMBER CS03322FB03
J 0
(1150 3075);
DISPLAY 0.638298 (1150 3075);
DISPLAY INVISIBLE (1150 3075);
FORCEPROP 1 LAST MATERIAL CHIP
J 0
(1575 3025);
DISPLAY 0.510638 (1575 3025);
FORCEPROP 1 LAST TOLERANCE 1%
J 0
(1500 3025);
DISPLAY 0.510638 (1500 3025);
FORCEPROP 1 LAST VALUE 33.2
J 2
(1475 3025);
DISPLAY 0.510638 (1475 3025);
FORCEPROP 1 LAST $LOCATION R3601
J 0
(1025 3025);
DISPLAY 0.787234 (1025 3025);
FORCEPROP 1 LASTPIN (1175 3025) $PN 1
J 0
(1187 3037);
DISPLAY 0.787234 (1187 3037);
FORCEPROP 1 LASTPIN (1375 3025) $PN 2
J 0
(1337 3037);
DISPLAY 0.787234 (1337 3037);
FORCEPROP 1 LAST WATTAGE 1/16W
J 2
(1475 3125);
DISPLAY 0.638298 (1475 3125);
DISPLAY INVISIBLE (1475 3125);
FORCEPROP 1 LAST PACK_TYPE 0402LF
J 0
(1625 3025);
DISPLAY 0.638298 (1625 3025);
DISPLAY INVISIBLE (1625 3025);
FORCEPROP 2 LAST CDS_LIB pure_quanta
J 0
(1275 3025);
PAINT MONO (1275 3025);
DISPLAY INVISIBLE (1275 3025);
FORCEPROP 1 LAST PATH I39
J 0
(1225 3175);
DISPLAY 0.978723 (1225 3175);
PAINT WHITE (1225 3175);
DISPLAY INVISIBLE (1225 3175);
FORCEPROP 2 LAST CDS_LOCATION R3601
J 0
(1225 3225);
DISPLAY 1.021277 (1225 3225);
DISPLAY INVISIBLE (1225 3225);
FORCEPROP 2 LAST $SEC 1
J 0
(1225 3225);
DISPLAY 0.680851 (1225 3225);
PAINT MONO (1225 3225);
DISPLAY INVISIBLE (1225 3225);
FORCEPROP 2 LAST CDS_SEC 1
J 0
(1225 3225);
DISPLAY 1.021277 (1225 3225);
DISPLAY INVISIBLE (1225 3225);
FORCEADD Q_RES..1
(625 3275);
FORCEPROP 1 LAST PART_NUMBER CS24702FB06
J 0
(200 3275);
DISPLAY 0.510638 (200 3275);
DISPLAY INVISIBLE (200 3275);
FORCEPROP 1 LAST WATTAGE 1/16W
J 2
(950 3275);
DISPLAY 0.510638 (950 3275);
FORCEPROP 1 LAST VALUE 4.7K
J 2
(825 3275);
DISPLAY 0.510638 (825 3275);
FORCEPROP 1 LAST TOLERANCE 1%
J 0
(950 3275);
DISPLAY 0.510638 (950 3275);
FORCEPROP 1 LAST MATERIAL EMPTY
J 0
(1000 3275);
DISPLAY 0.510638 (1000 3275);
PAINT RED (1000 3275);
FORCEPROP 1 LAST PACK_TYPE 0402LF
J 0
(1100 3275);
DISPLAY 0.510638 (1100 3275);
FORCEPROP 1 LAST $LOCATION R3617
J 0
(500 3275);
DISPLAY 0.638298 (500 3275);
FORCEPROP 1 LASTPIN (525 3275) $PN 1
J 0
(537 3287);
DISPLAY 0.787234 (537 3287);
PAINT MONO (537 3287);
FORCEPROP 1 LASTPIN (725 3275) $PN 2
J 0
(687 3287);
DISPLAY 0.787234 (687 3287);
PAINT MONO (687 3287);
FORCEPROP 2 LAST CDS_LIB pure_quanta
J 0
(625 3275);
DISPLAY INVISIBLE (625 3275);
FORCEPROP 1 LAST PATH I40
J 0
(575 3425);
DISPLAY 0.978723 (575 3425);
PAINT WHITE (575 3425);
DISPLAY INVISIBLE (575 3425);
FORCEPROP 0 LAST CDS_LOCATION R3617
J 0
(500 3325);
DISPLAY 1.021277 (500 3325);
DISPLAY INVISIBLE (500 3325);
FORCEPROP 0 LAST $SEC 1
J 0
(500 3325);
DISPLAY 0.680851 (500 3325);
PAINT MONO (500 3325);
DISPLAY INVISIBLE (500 3325);
FORCEPROP 0 LAST CDS_SEC 1
J 0
(500 3325);
DISPLAY 1.021277 (500 3325);
DISPLAY INVISIBLE (500 3325);
FORCEADD Q_RES..1
(1300 2475);
FORCEPROP 1 LAST PART_NUMBER CS01002FB07
J 0
(1150 2525);
DISPLAY 0.638298 (1150 2525);
DISPLAY INVISIBLE (1150 2525);
FORCEPROP 1 LAST PACK_TYPE 0402LF
J 0
(1425 2425);
DISPLAY 0.638298 (1425 2425);
FORCEPROP 1 LAST VALUE 10
J 2
(1250 2425);
DISPLAY 0.638298 (1250 2425);
FORCEPROP 1 LAST TOLERANCE 1%
J 0
(1350 2425);
DISPLAY 0.638298 (1350 2425);
FORCEPROP 1 LAST MATERIAL CHIP
J 0
(1325 2375);
DISPLAY 0.638298 (1325 2375);
FORCEPROP 1 LAST WATTAGE 1/16W
J 2
(1300 2375);
DISPLAY 0.638298 (1300 2375);
FORCEPROP 1 LAST $LOCATION R3602
J 0
(1050 2475);
DISPLAY 0.638298 (1050 2475);
FORCEPROP 1 LASTPIN (1200 2475) $PN 1
J 0
(1212 2487);
DISPLAY 0.787234 (1212 2487);
PAINT MONO (1212 2487);
FORCEPROP 1 LASTPIN (1400 2475) $PN 2
J 0
(1362 2487);
DISPLAY 0.787234 (1362 2487);
PAINT MONO (1362 2487);
FORCEPROP 2 LAST CDS_LIB pure_quanta
J 0
(1300 2475);
DISPLAY INVISIBLE (1300 2475);
FORCEPROP 1 LAST PATH I41
J 0
(1250 2625);
DISPLAY 0.978723 (1250 2625);
PAINT WHITE (1250 2625);
DISPLAY INVISIBLE (1250 2625);
FORCEPROP 0 LAST CDS_LOCATION R3602
J 0
(1150 2575);
DISPLAY 1.021277 (1150 2575);
DISPLAY INVISIBLE (1150 2575);
FORCEPROP 0 LAST $SEC 1
J 0
(1150 2575);
DISPLAY 0.680851 (1150 2575);
PAINT MONO (1150 2575);
DISPLAY INVISIBLE (1150 2575);
FORCEPROP 0 LAST CDS_SEC 1
J 0
(1150 2575);
DISPLAY 1.021277 (1150 2575);
DISPLAY INVISIBLE (1150 2575);
FORCEADD Q_RES..1
(1300 2200);
FORCEPROP 1 LAST PART_NUMBER CS01002FB07
J 0
(1150 2250);
DISPLAY 0.638298 (1150 2250);
DISPLAY INVISIBLE (1150 2250);
FORCEPROP 1 LAST MATERIAL CHIP
J 0
(1325 2100);
DISPLAY 0.638298 (1325 2100);
FORCEPROP 1 LAST WATTAGE 1/16W
J 2
(1300 2100);
DISPLAY 0.638298 (1300 2100);
FORCEPROP 1 LAST PACK_TYPE 0402LF
J 0
(1425 2150);
DISPLAY 0.638298 (1425 2150);
FORCEPROP 1 LAST VALUE 10
J 2
(1250 2150);
DISPLAY 0.638298 (1250 2150);
FORCEPROP 1 LAST TOLERANCE 1%
J 0
(1350 2150);
DISPLAY 0.638298 (1350 2150);
FORCEPROP 1 LAST $LOCATION R3603
J 0
(1050 2200);
DISPLAY 0.638298 (1050 2200);
FORCEPROP 1 LASTPIN (1200 2200) $PN 1
J 0
(1212 2212);
DISPLAY 0.787234 (1212 2212);
PAINT MONO (1212 2212);
FORCEPROP 1 LASTPIN (1400 2200) $PN 2
J 0
(1362 2212);
DISPLAY 0.787234 (1362 2212);
PAINT MONO (1362 2212);
FORCEPROP 2 LAST CDS_LIB pure_quanta
J 0
(1300 2200);
DISPLAY INVISIBLE (1300 2200);
FORCEPROP 1 LAST PATH I43
J 0
(1250 2350);
DISPLAY 0.978723 (1250 2350);
PAINT WHITE (1250 2350);
DISPLAY INVISIBLE (1250 2350);
FORCEPROP 0 LAST CDS_LOCATION R3603
J 0
(1150 2300);
DISPLAY 1.021277 (1150 2300);
DISPLAY INVISIBLE (1150 2300);
FORCEPROP 0 LAST $SEC 1
J 0
(1150 2300);
DISPLAY 0.680851 (1150 2300);
PAINT MONO (1150 2300);
DISPLAY INVISIBLE (1150 2300);
FORCEPROP 0 LAST CDS_SEC 1
J 0
(1150 2300);
DISPLAY 1.021277 (1150 2300);
DISPLAY INVISIBLE (1150 2300);
FORCEADD UNIVERSAL_GND..1
(200 3150);
FORCEPROP 3 LASTPIN (200 3200) SIG_NAME GND\g
J 0
(210 3210);
DISPLAY 0.659574 (210 3210);
PAINT MONO (210 3210);
DISPLAY INVISIBLE (210 3210);
FORCEPROP 1 LAST PATH I45
J 0
(275 3150);
DISPLAY 0.872340 (275 3150);
PAINT AQUA (275 3150);
DISPLAY INVISIBLE (275 3150);
FORCEPROP 2 LAST CDS_LIB logical_power
J 0
(200 3150);
DISPLAY INVISIBLE (200 3150);
FORCEPROP 1 LAST HDL_POWER GND
J 1
(225 3075);
DISPLAY 0.872340 (225 3075);
PAINT GREEN (225 3075);
DISPLAY INVISIBLE (225 3075);
FORCEADD OFFPAGE..1
(75 3075);
FORCEPROP 2 LAST $XR0 232 
J 0
(-177 3075);
DISPLAY 0.638298 (-177 3075);
PAINT MONO (-177 3075);
FORCEPROP 1 LAST COMMENT_BODY TRUE
J 0
(200 2975);
DISPLAY 0.872340 (200 2975);
PAINT GREEN (200 2975);
DISPLAY INVISIBLE (200 2975);
FORCEPROP 1 LAST OFFPAGE TRUE
J 0
(400 2950);
DISPLAY 0.872340 (400 2950);
DISPLAY INVISIBLE (400 2950);
FORCEPROP 2 LAST CDS_LIB standard
J 0
(75 3075);
DISPLAY INVISIBLE (75 3075);
FORCEPROP 2 LAST PATH I46
J 0
(125 3150);
DISPLAY 1.021277 (125 3150);
DISPLAY INVISIBLE (125 3150);
FORCEADD OFFPAGE..3
R 2
(75 3025);
FORCEPROP 2 LAST $XR0 232 
J 0
(-205 3025);
DISPLAY 0.638298 (-205 3025);
PAINT MONO (-205 3025);
FORCEPROP 2 LAST CDS_LIB standard
J 2
(75 3025);
PAINT MONO (75 3025);
DISPLAY INVISIBLE (75 3025);
FORCEPROP 1 LAST COMMENT_BODY TRUE
J 2
(125 2925);
DISPLAY 0.872340 (125 2925);
PAINT GREEN (125 2925);
DISPLAY INVISIBLE (125 2925);
FORCEPROP 1 LAST OFFPAGE TRUE
J 2
(-250 2900);
DISPLAY 0.872340 (-250 2900);
DISPLAY INVISIBLE (-250 2900);
FORCEPROP 2 LAST PATH I47
J 0
(-125 3075);
DISPLAY 1.021277 (-125 3075);
DISPLAY INVISIBLE (-125 3075);
FORCEADD UNIVERSAL_GND..1
(-500 2975);
FORCEPROP 3 LASTPIN (-500 3025) SIG_NAME GND\g
J 0
(-490 3035);
DISPLAY 0.659574 (-490 3035);
PAINT MONO (-490 3035);
DISPLAY INVISIBLE (-490 3035);
FORCEPROP 1 LAST HDL_POWER GND
J 1
(-475 2900);
DISPLAY 0.872340 (-475 2900);
PAINT GREEN (-475 2900);
DISPLAY INVISIBLE (-475 2900);
FORCEPROP 2 LAST CDS_LIB logical_power
J 0
(-500 2975);
DISPLAY INVISIBLE (-500 2975);
FORCEPROP 1 LAST PATH I49
J 0
(-425 2975);
DISPLAY 0.872340 (-425 2975);
PAINT AQUA (-425 2975);
DISPLAY INVISIBLE (-425 2975);
FORCEADD Q_CAP..1
(-500 3250);
FORCEPROP 1 LAST PART_NUMBER CH4104K1B00
J 0
(-450 3100);
DISPLAY 0.808511 (-450 3100);
DISPLAY INVISIBLE (-450 3100);
FORCEPROP 1 LAST PACK_TYPE 0402
J 0
(-450 3100);
DISPLAY 0.638298 (-450 3100);
FORCEPROP 1 LAST VALUE 0.1UF
J 0
(-450 3300);
DISPLAY 0.638298 (-450 3300);
FORCEPROP 1 LAST VOLTAGE 25V
J 0
(-450 3250);
DISPLAY 0.638298 (-450 3250);
FORCEPROP 1 LAST TOLERANCE 10%
J 0
(-450 3200);
DISPLAY 0.638298 (-450 3200);
FORCEPROP 1 LAST MATERIAL X7R
J 0
(-450 3150);
DISPLAY 0.638298 (-450 3150);
FORCEPROP 1 LAST $LOCATION C2024
J 0
(-450 3350);
DISPLAY 0.978723 (-450 3350);
FORCEPROP 1 LASTPIN (-500 3350) $PN 1
J 0
(-490 3330);
DISPLAY 0.787234 (-490 3330);
PAINT MONO (-490 3330);
FORCEPROP 1 LASTPIN (-500 3150) $PN 2
J 0
(-490 3130);
DISPLAY 0.787234 (-490 3130);
PAINT MONO (-490 3130);
FORCEPROP 2 LAST CDS_LIB pure_quanta
J 0
(-500 3250);
DISPLAY INVISIBLE (-500 3250);
FORCEPROP 1 LAST PATH I50
J 0
(-450 3400);
DISPLAY 0.978723 (-450 3400);
PAINT WHITE (-450 3400);
DISPLAY INVISIBLE (-450 3400);
FORCEPROP 0 LAST CDS_LOCATION C2024
J 0
(-450 3400);
DISPLAY 1.021277 (-450 3400);
DISPLAY INVISIBLE (-450 3400);
FORCEPROP 0 LAST $SEC 1
J 0
(-450 3400);
DISPLAY 0.680851 (-450 3400);
PAINT MONO (-450 3400);
DISPLAY INVISIBLE (-450 3400);
FORCEPROP 0 LAST CDS_SEC 1
J 0
(-450 3400);
DISPLAY 1.021277 (-450 3400);
DISPLAY INVISIBLE (-450 3400);
FORCEADD Q_CAP..1
(1650 2325);
FORCEPROP 1 LAST PART_NUMBER CH4104K1B00
J 0
(1700 2275);
DISPLAY 0.510638 (1700 2275);
DISPLAY INVISIBLE (1700 2275);
FORCEPROP 1 LAST VALUE 0.1UF
J 0
(1700 2375);
DISPLAY 0.510638 (1700 2375);
FORCEPROP 1 LAST VOLTAGE 25V
J 0
(1700 2350);
DISPLAY 0.510638 (1700 2350);
FORCEPROP 1 LAST TOLERANCE 10%
J 0
(1700 2325);
DISPLAY 0.510638 (1700 2325);
FORCEPROP 1 LAST MATERIAL X7R
J 0
(1700 2300);
DISPLAY 0.510638 (1700 2300);
FORCEPROP 1 LAST PACK_TYPE 0402
J 0
(1700 2250);
DISPLAY 0.510638 (1700 2250);
FORCEPROP 1 LAST $LOCATION C2027
J 0
(1700 2425);
DISPLAY 0.978723 (1700 2425);
FORCEPROP 1 LASTPIN (1650 2425) $PN 1
J 0
(1660 2405);
DISPLAY 0.787234 (1660 2405);
PAINT MONO (1660 2405);
FORCEPROP 1 LASTPIN (1650 2225) $PN 2
J 0
(1660 2205);
DISPLAY 0.787234 (1660 2205);
PAINT MONO (1660 2205);
FORCEPROP 1 LAST PATH I77
J 0
(1700 2475);
DISPLAY 0.978723 (1700 2475);
PAINT WHITE (1700 2475);
DISPLAY INVISIBLE (1700 2475);
FORCEPROP 2 LAST CDS_LIB pure_quanta
J 0
(1650 2325);
DISPLAY INVISIBLE (1650 2325);
FORCEPROP 0 LAST CDS_LOCATION C2027
J 0
(1700 2475);
DISPLAY 1.021277 (1700 2475);
DISPLAY INVISIBLE (1700 2475);
FORCEPROP 0 LAST $SEC 1
J 0
(1700 2475);
DISPLAY 0.680851 (1700 2475);
PAINT MONO (1700 2475);
DISPLAY INVISIBLE (1700 2475);
FORCEPROP 0 LAST CDS_SEC 1
J 0
(1700 2475);
DISPLAY 1.021277 (1700 2475);
DISPLAY INVISIBLE (1700 2475);
FORCEADD UNIVERSAL_POWER..1
(-100 2825);
FORCEPROP 3 LASTPIN (-100 2775) SIG_NAME P3V3_OCP_SFF_R\g
J 0
(-90 2785);
DISPLAY 0.659574 (-90 2785);
PAINT MONO (-90 2785);
DISPLAY INVISIBLE (-90 2785);
FORCEPROP 1 LAST HDL_POWER P3V3_OCP_SFF_R
J 1
(-100 2875);
DISPLAY 0.872340 (-100 2875);
PAINT GREEN (-100 2875);
FORCEPROP 1 LAST PATH I79
J 0
(-50 2850);
DISPLAY 0.872340 (-50 2850);
PAINT AQUA (-50 2850);
DISPLAY INVISIBLE (-50 2850);
FORCEPROP 2 LAST CDS_LIB logical_power
J 0
(-100 2825);
DISPLAY INVISIBLE (-100 2825);
FORCEADD UNIVERSAL_POWER..1
(-250 3575);
FORCEPROP 3 LASTPIN (-250 3525) SIG_NAME P3V3_OCP_SFF_R\g
J 0
(-240 3535);
DISPLAY 0.659574 (-240 3535);
PAINT MONO (-240 3535);
DISPLAY INVISIBLE (-240 3535);
FORCEPROP 1 LAST HDL_POWER P3V3_OCP_SFF_R
J 1
(-250 3625);
DISPLAY 0.872340 (-250 3625);
PAINT GREEN (-250 3625);
FORCEPROP 1 LAST PATH I80
J 0
(-200 3600);
DISPLAY 0.872340 (-200 3600);
PAINT AQUA (-200 3600);
DISPLAY INVISIBLE (-200 3600);
FORCEPROP 2 LAST CDS_LIB logical_power
J 0
(-250 3575);
DISPLAY INVISIBLE (-250 3575);
FORCEADD UNIVERSAL_POWER..1
(-1175 2825);
FORCEPROP 3 LASTPIN (-1175 2775) SIG_NAME P3V3_OCP_SFF\g
J 0
(-1165 2785);
DISPLAY 0.659574 (-1165 2785);
PAINT MONO (-1165 2785);
DISPLAY INVISIBLE (-1165 2785);
FORCEPROP 1 LAST HDL_POWER P3V3_OCP_SFF
J 1
(-1175 2875);
DISPLAY 0.872340 (-1175 2875);
PAINT GREEN (-1175 2875);
FORCEPROP 2 LAST CDS_LIB logical_power
J 0
(-1175 2825);
DISPLAY INVISIBLE (-1175 2825);
FORCEPROP 1 LAST PATH I81
J 0
(-1125 2850);
DISPLAY 0.872340 (-1125 2850);
PAINT AQUA (-1125 2850);
DISPLAY INVISIBLE (-1125 2850);
FORCEADD UNIVERSAL_POWER..1
(1825 4125);
FORCEPROP 3 LASTPIN (1825 4075) SIG_NAME P3V3_AUX\g
J 0
(1835 4085);
DISPLAY 0.659574 (1835 4085);
PAINT MONO (1835 4085);
DISPLAY INVISIBLE (1835 4085);
FORCEPROP 1 LAST HDL_POWER P3V3_AUX
J 1
(1825 4175);
DISPLAY 0.872340 (1825 4175);
PAINT GREEN (1825 4175);
FORCEPROP 2 LAST CDS_LIB logical_power
J 0
(1825 4125);
DISPLAY INVISIBLE (1825 4125);
FORCEPROP 1 LAST PATH I87
J 0
(1875 4150);
DISPLAY 0.872340 (1875 4150);
PAINT AQUA (1875 4150);
DISPLAY INVISIBLE (1875 4150);
FORCEADD Q_RES..2
(1825 3700);
FORCEPROP 1 LAST PART_NUMBER CS24702FB06
J 0
(1865 3575);
DISPLAY 0.510638 (1865 3575);
DISPLAY INVISIBLE (1865 3575);
FORCEPROP 1 LAST VALUE 4.7K
J 0
(1870 3775);
DISPLAY 0.510638 (1870 3775);
FORCEPROP 1 LAST TOLERANCE 1%
J 0
(1870 3725);
DISPLAY 0.510638 (1870 3725);
FORCEPROP 1 LAST MATERIAL EMPTY
J 0
(1865 3625);
DISPLAY 0.510638 (1865 3625);
PAINT RED (1865 3625);
FORCEPROP 1 LAST WATTAGE 1/16W
J 0
(1865 3675);
DISPLAY 0.510638 (1865 3675);
FORCEPROP 1 LAST PACK_TYPE 0402LF
J 0
(1865 3525);
DISPLAY 0.510638 (1865 3525);
FORCEPROP 1 LAST $LOCATION R3628
J 0
(1870 3825);
DISPLAY 0.978723 (1870 3825);
FORCEPROP 1 LASTPIN (1825 3800) $PN 1
J 0
(1830 3762);
DISPLAY 0.787234 (1830 3762);
PAINT MONO (1830 3762);
FORCEPROP 1 LASTPIN (1825 3600) $PN 2
J 0
(1830 3610);
DISPLAY 0.787234 (1830 3610);
PAINT MONO (1830 3610);
FORCEPROP 2 LAST CDS_LIB pure_quanta
J 0
(1825 3700);
DISPLAY INVISIBLE (1825 3700);
FORCEPROP 1 LAST PATH I88
J 0
(1875 3875);
DISPLAY 0.978723 (1875 3875);
PAINT WHITE (1875 3875);
DISPLAY INVISIBLE (1875 3875);
FORCEPROP 0 LAST CDS_LOCATION R3628
J 0
(1875 3875);
DISPLAY 1.021277 (1875 3875);
DISPLAY INVISIBLE (1875 3875);
FORCEPROP 0 LAST $SEC 1
J 0
(1875 3875);
DISPLAY 0.680851 (1875 3875);
PAINT MONO (1875 3875);
DISPLAY INVISIBLE (1875 3875);
FORCEPROP 0 LAST CDS_SEC 1
J 0
(1875 3875);
DISPLAY 1.021277 (1875 3875);
DISPLAY INVISIBLE (1875 3875);
FORCEADD Q_RES..2
(1525 3700);
FORCEPROP 1 LAST PART_NUMBER CS24702FB06
J 0
(1565 3575);
DISPLAY 0.510638 (1565 3575);
DISPLAY INVISIBLE (1565 3575);
FORCEPROP 1 LAST VALUE 4.7K
J 0
(1570 3775);
DISPLAY 0.510638 (1570 3775);
FORCEPROP 1 LAST PACK_TYPE 0402LF
J 0
(1565 3525);
DISPLAY 0.510638 (1565 3525);
FORCEPROP 1 LAST MATERIAL CHIP
J 0
(1565 3625);
DISPLAY 0.510638 (1565 3625);
FORCEPROP 1 LAST WATTAGE 1/16W
J 0
(1565 3675);
DISPLAY 0.510638 (1565 3675);
FORCEPROP 1 LAST TOLERANCE 1%
J 0
(1570 3725);
DISPLAY 0.510638 (1570 3725);
FORCEPROP 1 LAST $LOCATION R3627
J 0
(1570 3825);
DISPLAY 0.978723 (1570 3825);
FORCEPROP 1 LASTPIN (1525 3800) $PN 1
J 0
(1530 3762);
DISPLAY 0.787234 (1530 3762);
PAINT MONO (1530 3762);
FORCEPROP 1 LASTPIN (1525 3600) $PN 2
J 0
(1530 3610);
DISPLAY 0.787234 (1530 3610);
PAINT MONO (1530 3610);
FORCEPROP 2 LAST CDS_LIB pure_quanta
J 0
(1525 3700);
DISPLAY INVISIBLE (1525 3700);
FORCEPROP 1 LAST PATH I89
J 0
(1575 3875);
DISPLAY 0.978723 (1575 3875);
PAINT WHITE (1575 3875);
DISPLAY INVISIBLE (1575 3875);
FORCEPROP 0 LAST CDS_LOCATION R3627
J 0
(1575 3875);
DISPLAY 1.021277 (1575 3875);
DISPLAY INVISIBLE (1575 3875);
FORCEPROP 0 LAST $SEC 1
J 0
(1575 3875);
DISPLAY 0.680851 (1575 3875);
PAINT MONO (1575 3875);
DISPLAY INVISIBLE (1575 3875);
FORCEPROP 0 LAST CDS_SEC 1
J 0
(1575 3875);
DISPLAY 1.021277 (1575 3875);
DISPLAY INVISIBLE (1575 3875);
FORCEADD DNS..2
(775 1000);
PAINT RED (775 1000);
FORCEPROP 1 LAST COMMENT_BODY TRUE
R 1
J 0
(850 775);
DISPLAY 0.872340 (850 775);
PAINT GREEN (850 775);
DISPLAY INVISIBLE (850 775);
FORCEPROP 2 LAST CDS_LIB mstr_misc
J 0
(775 1000);
DISPLAY INVISIBLE (775 1000);
FORCEADD DNS..2
(650 3275);
PAINT RED (650 3275);
FORCEPROP 2 LAST CDS_LIB mstr_misc
J 0
(650 3275);
DISPLAY INVISIBLE (650 3275);
FORCEPROP 1 LAST COMMENT_BODY TRUE
R 1
J 0
(725 3050);
DISPLAY 0.872340 (725 3050);
PAINT GREEN (725 3050);
DISPLAY INVISIBLE (725 3050);
FORCEADD DNS..2
(1825 3675);
PAINT RED (1825 3675);
FORCEPROP 2 LAST CDS_LIB mstr_misc
J 0
(1825 3675);
DISPLAY INVISIBLE (1825 3675);
FORCEPROP 1 LAST COMMENT_BODY TRUE
R 1
J 0
(1900 3450);
DISPLAY 0.872340 (1900 3450);
PAINT GREEN (1900 3450);
DISPLAY INVISIBLE (1900 3450);
FORCEADD QUANTA_TITLE_BLOCK_C..1
(6825 -1650);
FORCEPROP 0 LAST CDS_CON_LAST_MODIFIED Fri Aug 25 14:02:41 2023
J 0
(4940 -1635);
DISPLAY INVISIBLE (4940 -1635);
FORCEPROP 1 LAST CUSTOM_TXT_CDS <CON_LAST_MODIFIED>
J 0
(4940 -1635);
DISPLAY 0.978723 (4940 -1635);
FORCEPROP 2 LAST CUSTOM_TXT_CDS <XR_PAGE_TITLE>
J 0
(-1065 3600);
DISPLAY 0.638298 (-1065 3600);
PAINT PINK (-1065 3600);
DISPLAY INVISIBLE (-1065 3600);
FORCEPROP 1 LAST CUSTOM_TXT_CDS <NAME_2>
J 0
(3650 -1600);
FORCEPROP 1 LAST CUSTOM_TXT_CDS <NAME_1>
J 0
(3650 -1475);
FORCEPROP 1 LAST CUSTOM_TXT_CDS <Q_NUMBER>
J 0
(5422 -1547);
DISPLAY 1.212766 (5422 -1547);
FORCEPROP 1 LAST CUSTOM_TXT_CDS <Q_PROJ>
J 0
(4443 -1548);
DISPLAY 1.212766 (4443 -1548);
FORCEPROP 1 LAST CUSTOM_TXT_CDS <Q_REV>
J 0
(6641 -1547);
DISPLAY 1.212766 (6641 -1547);
FORCEPROP 1 LAST CUSTOM_TXT_CDS <CON_PAGE_NUM> OF <CON_TOTAL_PAGES>
J 0
(6379 -1632);
DISPLAY 0.978723 (6379 -1632);
FORCEPROP 1 LAST Q_TITLE POWER MONITOR (1/2)
J 0
(-2500 -1625);
DISPLAY 2.446809 (-2500 -1625);
PAINT GREEN (-2500 -1625);
FORCEPROP 1 LAST Q_DEPT 
J 1
(3062 -1601);
DISPLAY 1.957447 (3062 -1601);
PAINT GREEN (3062 -1601);
FORCEPROP 2 LAST CDS_XR_PAGE_TITLE CR-171 : @S9S_MB_2U_LIB.S9S_MB_2U(SCH_1):PAGE171
J 0
(-1065 3600);
DISPLAY 0.638298 (-1065 3600);
PAINT PINK (-1065 3600);
DISPLAY INVISIBLE (-1065 3600);
FORCEPROP 2 LAST CDS_LIB pure_quanta
J 0
(6825 -1650);
DISPLAY INVISIBLE (6825 -1650);
FORCEPROP 1 LAST CDS_LMAN_SYM_OUTLINE -9475,6775,100,-125
J 0
(6825 -1650);
DISPLAY 0.468085 (6825 -1650);
PAINT GREEN (6825 -1650);
DISPLAY INVISIBLE (6825 -1650);
FORCEPROP 1 LAST COMMENT_BODY TRUE
J 0
(6837 -1663);
DISPLAY 0.978723 (6837 -1663);
PAINT GREEN (6837 -1663);
DISPLAY INVISIBLE (6837 -1663);
FORCEPROP 2 LAST PAGE_BORDER TRUE
J 0
(-1065 3600);
DISPLAY 0.638298 (-1065 3600);
PAINT PINK (-1065 3600);
DISPLAY INVISIBLE (-1065 3600);
WIRE 16 -1 (4150 3875)(4150 3925);
WIRE 16 -1 (4125 1275)(4125 1325);
WIRE 16 -1 (2425 1425)(2425 1300);
WIRE 16 -1 (-250 3525)(-250 3475);
WIRE 16 -1 (-1175 2675)(-1175 2775);
WIRE 16 -1 (-1175 2675)(-875 2675);
WIRE 16 -1 (2425 4025)(2425 3900);
WIRE 16 -1 (-100 2675)(-100 2775);
WIRE 16 -1 (-275 2675)(-100 2675);
WIRE 16 -1 (-1175 75)(-1175 175);
WIRE 16 -1 (-1175 75)(-875 75);
WIRE 16 -1 (-250 925)(-250 875);
WIRE 16 -1 (-100 75)(-100 175);
WIRE 16 -1 (-275 75)(-100 75);
WIRE 16 -1 (1825 4075)(1825 4025);
WIRE 16 -1 (3400 2825)(3400 2475);
WIRE 16 -1 (3400 2875)(3400 2825);
WIRE 16 -1 (3275 2825)(3400 2825);
WIRE 16 -1 (3400 225)(3400 -125);
WIRE 16 -1 (3400 275)(3400 225);
WIRE 16 -1 (3275 225)(3400 225);
WIRE 16 -1 (-500 550)(-500 425);
WIRE 16 -1 (175 925)(175 1000);
WIRE 16 -1 (2175 975)(2175 850);
WIRE 16 -1 (-500 3150)(-500 3025);
WIRE 16 -1 (200 3200)(200 3275);
WIRE 16 -1 (2175 3575)(2175 3450);
WIRE 16 -1 (3275 2875)(3400 2875);
WIRE 16 -1 (3275 2975)(3900 2975);
FORCEPROP 2 LAST SIG_NAME NC_INA230_1_NC5
J 0
(3415 2985);
DISPLAY 0.638298 (3415 2985);
PAINT WHITE (3415 2985);
WIRE 16 -1 (4450 3325)(5500 3325);
FORCEPROP 2 LAST SIG_NAME OCP_SFF_P3V3_ADC_ALERT
J 0
(4840 3335);
DISPLAY 0.638298 (4840 3335);
PAINT WHITE (4840 3335);
WIRE 16 -1 (3275 3325)(4150 3325);
FORCEPROP 2 LAST SIG_NAME OCP_SFF_P3V3_ADC_ALERT_R
J 0
(3415 3335);
DISPLAY 0.638298 (3415 3335);
PAINT WHITE (3415 3335);
WIRE 16 -1 (4150 3325)(4250 3325);
WIRE 16 -1 (4150 3675)(4150 3325);
WIRE 16 2175 (3925 4150)(4600 4150);
WIRE 16 2175 (4600 4150)(4600 3550);
WIRE 16 2175 (3925 4150)(3925 3550);
WIRE 16 2175 (3925 3550)(4600 3550);
WIRE 16 -1 (3275 3175)(3900 3175);
FORCEPROP 2 LAST SIG_NAME NC_INA230_1_NC1
J 0
(3415 3185);
DISPLAY 0.638298 (3415 3185);
PAINT WHITE (3415 3185);
WIRE 16 -1 (3275 3125)(3900 3125);
FORCEPROP 2 LAST SIG_NAME NC_INA230_1_NC2
J 0
(3415 3135);
DISPLAY 0.638298 (3415 3135);
PAINT WHITE (3415 3135);
WIRE 16 -1 (3275 3075)(3900 3075);
FORCEPROP 2 LAST SIG_NAME NC_INA230_1_NC3
J 0
(3415 3085);
DISPLAY 0.638298 (3415 3085);
PAINT WHITE (3415 3085);
WIRE 16 -1 (3275 3225)(3900 3225);
FORCEPROP 2 LAST SIG_NAME NC_INA230_1_NC0
J 0
(3415 3235);
DISPLAY 0.638298 (3415 3235);
PAINT WHITE (3415 3235);
WIRE 16 -1 (3275 3025)(3900 3025);
FORCEPROP 2 LAST SIG_NAME NC_INA230_1_NC4
J 0
(3415 3035);
DISPLAY 0.638298 (3415 3035);
PAINT WHITE (3415 3035);
WIRE 16 -1 (2425 3325)(2475 3325);
WIRE 16 -1 (2425 3900)(2425 3325);
WIRE 16 -1 (2175 3775)(2175 3900);
WIRE 16 -1 (2175 3900)(2425 3900);
WIRE 16 -1 (725 3350)(1825 3350);
FORCEPROP 2 LAST SIG_NAME INA230_1_A1
J 0
(1865 3360);
DISPLAY 0.638298 (1865 3360);
PAINT WHITE (1865 3360);
WIRE 16 -1 (1825 3600)(1825 3350);
WIRE 16 -1 (2375 3225)(2475 3225);
WIRE 16 -1 (1825 3350)(2375 3350);
WIRE 16 -1 (2375 3350)(2375 3225);
WIRE 16 -1 (725 3275)(1525 3275);
WIRE 16 -1 (1525 3600)(1525 3275);
WIRE 16 -1 (1525 3275)(2325 3275);
FORCEPROP 2 LAST SIG_NAME INA230_1_A0
J 0
(1865 3285);
DISPLAY 0.638298 (1865 3285);
PAINT WHITE (1865 3285);
WIRE 16 -1 (2325 3275)(2325 3175);
WIRE 16 -1 (2325 3175)(2475 3175);
WIRE 16 -1 (1375 3075)(2475 3075);
FORCEPROP 2 LAST SIG_NAME SMB_INA230_1_3V3AUX_SCL_R1
J 0
(1690 3085);
DISPLAY 0.680851 (1690 3085);
PAINT WHITE (1690 3085);
WIRE 16 -1 (1375 3025)(2475 3025);
FORCEPROP 2 LAST SIG_NAME SMB_INA230_1_3V3AUX_SDA_R1
J 0
(1690 3035);
DISPLAY 0.680851 (1690 3035);
PAINT WHITE (1690 3035);
WIRE 16 -1 (-500 3350)(-500 3475);
WIRE 16 -1 (-500 3475)(-250 3475);
WIRE 16 -1 (-250 3475)(-250 2925);
WIRE 16 -1 (2475 2925)(-250 2925);
WIRE 16 -1 (1650 2475)(1400 2475);
WIRE 16 -1 (1650 2425)(1650 2475);
WIRE 16 -1 (2250 2475)(1650 2475);
FORCEPROP 2 LAST SIG_NAME VSENSE_P3V3_INA230_1_INP
J 0
(1665 2485);
DISPLAY 0.510638 (1665 2485);
PAINT WHITE (1665 2485);
WIRE 16 -1 (2250 2475)(2250 2875);
WIRE 16 -1 (2250 2875)(2475 2875);
WIRE 16 -1 (1400 2200)(1650 2200);
WIRE 16 -1 (1650 2225)(1650 2200);
WIRE 16 -1 (2350 2200)(1650 2200);
FORCEPROP 2 LAST SIG_NAME VSENSE_P3V3_INA230_1_INN
J 0
(1690 2210);
DISPLAY 0.510638 (1690 2210);
PAINT WHITE (1690 2210);
WIRE 16 -1 (2350 2200)(2350 2825);
WIRE 16 -1 (2350 2825)(2475 2825);
WIRE 16 -1 (3275 575)(3900 575);
FORCEPROP 2 LAST SIG_NAME NC_INA230_2_NC1
J 0
(3415 585);
DISPLAY 0.638298 (3415 585);
PAINT WHITE (3415 585);
WIRE 16 -1 (4450 725)(5500 725);
FORCEPROP 2 LAST SIG_NAME E1S_0_P3V3_ADC_ALERT
J 0
(4840 735);
DISPLAY 0.638298 (4840 735);
PAINT WHITE (4840 735);
WIRE 16 -1 (3275 725)(4125 725);
FORCEPROP 2 LAST SIG_NAME E1S_0_P3V3_ADC_ALERT_R
J 0
(3415 735);
DISPLAY 0.638298 (3415 735);
PAINT WHITE (3415 735);
WIRE 16 -1 (4125 725)(4250 725);
WIRE 16 -1 (4125 1075)(4125 725);
WIRE 16 -1 (3275 275)(3400 275);
WIRE 16 2175 (3925 1525)(4600 1525);
WIRE 16 2175 (4600 1525)(4600 925);
WIRE 16 2175 (3925 1525)(3925 925);
WIRE 16 2175 (3925 925)(4600 925);
WIRE 16 -1 (3275 475)(3900 475);
FORCEPROP 2 LAST SIG_NAME NC_INA230_2_NC3
J 0
(3415 485);
DISPLAY 0.638298 (3415 485);
PAINT WHITE (3415 485);
WIRE 16 -1 (3275 425)(3900 425);
FORCEPROP 2 LAST SIG_NAME NC_INA230_2_NC4
J 0
(3415 435);
DISPLAY 0.638298 (3415 435);
PAINT WHITE (3415 435);
WIRE 16 -1 (3275 525)(3900 525);
FORCEPROP 2 LAST SIG_NAME NC_INA230_2_NC2
J 0
(3415 535);
DISPLAY 0.638298 (3415 535);
PAINT WHITE (3415 535);
WIRE 16 -1 (3275 625)(3900 625);
FORCEPROP 2 LAST SIG_NAME NC_INA230_2_NC0
J 0
(3415 635);
DISPLAY 0.638298 (3415 635);
PAINT WHITE (3415 635);
WIRE 16 -1 (3275 375)(3900 375);
FORCEPROP 2 LAST SIG_NAME NC_INA230_2_NC5
J 0
(3415 385);
DISPLAY 0.638298 (3415 385);
PAINT WHITE (3415 385);
WIRE 16 -1 (1400 -400)(1650 -400);
WIRE 16 -1 (1650 -375)(1650 -400);
WIRE 16 -1 (2350 -400)(1650 -400);
FORCEPROP 2 LAST SIG_NAME VSENSE_P3V3_INA230_2_INN
J 0
(1690 -390);
DISPLAY 0.510638 (1690 -390);
PAINT WHITE (1690 -390);
WIRE 16 -1 (2350 -400)(2350 225);
WIRE 16 -1 (2350 225)(2475 225);
WIRE 16 -1 (1650 -125)(1400 -125);
WIRE 16 -1 (1650 -175)(1650 -125);
WIRE 16 -1 (2250 -125)(1650 -125);
FORCEPROP 2 LAST SIG_NAME VSENSE_P3V3_INA230_2_INP
J 0
(1665 -115);
DISPLAY 0.510638 (1665 -115);
PAINT WHITE (1665 -115);
WIRE 16 -1 (2250 -125)(2250 275);
WIRE 16 -1 (2250 275)(2475 275);
WIRE 16 -1 (-500 750)(-500 875);
WIRE 16 -1 (-500 875)(-250 875);
WIRE 16 -1 (-250 875)(-250 325);
WIRE 16 -1 (2475 325)(-250 325);
WIRE 16 -1 (1550 725)(1550 425);
WIRE 16 -1 (1550 425)(2475 425);
FORCEPROP 2 LAST SIG_NAME SMB_INA230_2_3V3AUX_SDA_R1
J 0
(1690 435);
DISPLAY 0.680851 (1690 435);
PAINT WHITE (1690 435);
WIRE 16 -1 (1375 425)(1550 425);
WIRE 16 -1 (1375 475)(2475 475);
FORCEPROP 2 LAST SIG_NAME SMB_INA230_2_3V3AUX_SCL_R1
J 0
(1690 485);
DISPLAY 0.680851 (1690 485);
PAINT WHITE (1690 485);
WIRE 16 -1 (1550 1000)(850 1000);
FORCEPROP 2 LAST SIG_NAME INA230_2_A0
J 0
(1540 1010);
DISPLAY 0.638298 (1540 1010);
PAINT WHITE (1540 1010);
WIRE 16 -1 (1550 925)(1550 1000);
WIRE 16 -1 (1925 1000)(1550 1000);
WIRE 16 -1 (1925 1000)(1925 575);
WIRE 16 -1 (1925 575)(2475 575);
WIRE 16 -1 (2050 1075)(850 1075);
FORCEPROP 2 LAST SIG_NAME INA230_2_A1
J 0
(1540 1085);
DISPLAY 0.638298 (1540 1085);
PAINT WHITE (1540 1085);
WIRE 16 -1 (2050 1075)(2050 650);
WIRE 16 -1 (2050 650)(2475 650);
WIRE 16 -1 (2475 650)(2475 625);
WIRE 16 -1 (2425 725)(2475 725);
WIRE 16 -1 (2425 1300)(2425 725);
WIRE 16 -1 (2175 1175)(2175 1300);
WIRE 16 -1 (2175 1300)(2425 1300);
WIRE 16 -1 (-875 2675)(-700 2675);
WIRE 16 -1 (-875 2200)(-875 2675);
WIRE 16 -1 (-875 2200)(1200 2200);
WIRE 16 -1 (-875 75)(-700 75);
WIRE 16 -1 (-875 -400)(-875 75);
WIRE 16 -1 (-875 -400)(1200 -400);
WIRE 16 -1 (-500 75)(-275 75);
WIRE 16 -1 (-275 -125)(-275 75);
WIRE 16 -1 (-275 -125)(1200 -125);
WIRE 16 -1 (-500 2675)(-275 2675);
WIRE 16 -1 (-275 2475)(-275 2675);
WIRE 16 -1 (-275 2475)(1200 2475);
WIRE 16 -1 (1525 3800)(1525 4025);
WIRE 16 -1 (1525 4025)(1825 4025);
WIRE 16 -1 (1825 4025)(1825 3800);
WIRE 16 -1 (125 3025)(1175 3025);
FORCEPROP 2 LAST SIG_NAME SMB_INA230_1_3V3AUX_SDA_R
J 0
(190 3035);
DISPLAY 0.680851 (190 3035);
PAINT WHITE (190 3035);
WIRE 16 -1 (200 3275)(525 3275);
WIRE 16 -1 (200 3350)(200 3275);
WIRE 16 -1 (525 3350)(200 3350);
WIRE 16 -1 (125 3075)(1175 3075);
FORCEPROP 2 LAST SIG_NAME SMB_INA230_1_3V3AUX_SCL_R
J 0
(190 3085);
DISPLAY 0.680851 (190 3085);
PAINT WHITE (190 3085);
WIRE 16 -1 (175 1000)(650 1000);
WIRE 16 -1 (175 1075)(175 1000);
WIRE 16 -1 (650 1075)(175 1075);
WIRE 16 -1 (125 475)(1175 475);
FORCEPROP 2 LAST SIG_NAME SMB_INA230_2_3V3AUX_SCL_R
J 0
(190 485);
DISPLAY 0.680851 (190 485);
PAINT WHITE (190 485);
WIRE 16 -1 (125 425)(1175 425);
FORCEPROP 2 LAST SIG_NAME SMB_INA230_2_3V3AUX_SDA_R
J 0
(190 435);
DISPLAY 0.680851 (190 435);
PAINT WHITE (190 435);
DOT 1 (1825 4025);
DOT 1 (1825 3350);
DOT 1 (-875 75);
DOT 1 (-275 75);
DOT 1 (-250 875);
DOT 1 (1650 -125);
DOT 1 (1650 -400);
DOT 1 (1550 425);
DOT 1 (175 1000);
DOT 1 (1550 1000);
DOT 1 (2425 1300);
DOT 1 (-275 2675);
DOT 1 (-250 3475);
DOT 1 (200 3275);
DOT 1 (1650 2200);
DOT 1 (1650 2475);
DOT 1 (1525 3275);
DOT 1 (2425 3900);
DOT 1 (-875 2675);
DOT 1 (3400 225);
DOT 1 (4125 725);
DOT 1 (4150 3325);
DOT 1 (3400 2825);
FORCENOTE
20210929 MODIFY FOR GT
(-2400 4775) 0;
DISPLAY LEFT (-2400 4775);
DISPLAY 2.510638 (-2400 4775);
PAINT PINK (-2400 4775);
FORCENOTE
ADDRESS : 0X84
(2375 25) 0;
DISPLAY LEFT (2375 25);
DISPLAY 1.340425 (2375 25);
PAINT WHITE (2375 25);
FORCENOTE
20211130 ADD R4093,R4094 PU TO P3V3_AUX
(3175 1600) 0;
DISPLAY LEFT (3175 1600);
DISPLAY 1.276596 (3175 1600);
PAINT PINK (3175 1600);
FORCENOTE
ADDRESS : 0X82
(2425 2625) 0;
DISPLAY LEFT (2425 2625);
DISPLAY 1.340425 (2425 2625);
PAINT WHITE (2425 2625);
QUIT
